FILE_TYPE = MACRO_DRAWING;
SET COLOR_WIRE YELLOW;
SET COLOR_PROP ORANGE;
SET COLOR_DOT WHITE;
SET COLOR_ARC YELLOW;
SET COLOR_BODY GREEN;
SET COLOR_NOTE PURPLE;
SET PROP_DISPLAY VALUE;
SET PAGE_NUMBER P38;
FORCEADD GENOA_SP5..2
(-4725 3625);
FORCEPROP 1 LAST LOCATION U26
J 0
(-5370 6481);
DISPLAY 0.489362 (-5370 6481);
PAINT SKYBLUE (-5370 6481);
FORCEPROP 0 LAST $SEC 2
J 0
(-5350 6525);
DISPLAY 0.680851 (-5350 6525);
PAINT MONO (-5350 6525);
DISPLAY INVISIBLE (-5350 6525);
FORCEPROP 0 LAST CDS_SEC 2
J 0
(-5375 6425);
DISPLAY 1.021277 (-5375 6425);
DISPLAY INVISIBLE (-5375 6425);
FORCEPROP 0 LASTPIN (-5525 3025) $PN BC64
J 2
(-5535 3035);
DISPLAY 0.489362 (-5535 3035);
PAINT MONO (-5535 3035);
FORCEPROP 0 LASTPIN (-5525 2975) $PN BD63
J 2
(-5535 2985);
DISPLAY 0.489362 (-5535 2985);
PAINT MONO (-5535 2985);
FORCEPROP 0 LASTPIN (-5525 1875) $PN BF63
J 2
(-5535 1885);
DISPLAY 0.489362 (-5535 1885);
PAINT MONO (-5535 1885);
FORCEPROP 0 LASTPIN (-5525 1825) $PN BG64
J 2
(-5535 1835);
DISPLAY 0.489362 (-5535 1835);
PAINT MONO (-5535 1835);
FORCEPROP 0 LASTPIN (-5525 2175) $PN AT62
J 2
(-5535 2185);
DISPLAY 0.489362 (-5535 2185);
PAINT MONO (-5535 2185);
FORCEPROP 0 LASTPIN (-5525 2075) $PN AU62
J 2
(-5535 2085);
DISPLAY 0.489362 (-5535 2085);
PAINT MONO (-5535 2085);
FORCEPROP 0 LASTPIN (-5525 2875) $PN AV63
J 2
(-5535 2885);
DISPLAY 0.489362 (-5535 2885);
PAINT MONO (-5535 2885);
FORCEPROP 0 LASTPIN (-5525 2825) $PN AW62
J 2
(-5535 2835);
DISPLAY 0.489362 (-5535 2835);
PAINT MONO (-5535 2835);
FORCEPROP 0 LASTPIN (-5525 2725) $PN BN62
J 2
(-5535 2735);
DISPLAY 0.489362 (-5535 2735);
PAINT MONO (-5535 2735);
FORCEPROP 0 LASTPIN (-5525 1725) $PN AU64
J 2
(-5535 1735);
DISPLAY 0.489362 (-5535 1735);
PAINT MONO (-5535 1735);
FORCEPROP 0 LASTPIN (-5525 1675) $PN AV62
J 2
(-5535 1685);
DISPLAY 0.489362 (-5535 1685);
PAINT MONO (-5535 1685);
FORCEPROP 0 LASTPIN (-5525 1575) $PN BP62
J 2
(-5535 1585);
DISPLAY 0.489362 (-5535 1585);
PAINT MONO (-5535 1585);
FORCEPROP 0 LASTPIN (-5525 3875) $PN AW64
J 2
(-5535 3885);
DISPLAY 0.489362 (-5535 3885);
PAINT MONO (-5535 3885);
FORCEPROP 0 LASTPIN (-5525 3825) $PN AY63
J 2
(-5535 3835);
DISPLAY 0.489362 (-5535 3835);
PAINT MONO (-5535 3835);
FORCEPROP 0 LASTPIN (-5525 3775) $PN AY62
J 2
(-5535 3785);
DISPLAY 0.489362 (-5535 3785);
PAINT MONO (-5535 3785);
FORCEPROP 0 LASTPIN (-5525 3725) $PN BA62
J 2
(-5535 3735);
DISPLAY 0.489362 (-5535 3735);
PAINT MONO (-5535 3735);
FORCEPROP 0 LASTPIN (-5525 3675) $PN BA64
J 2
(-5535 3685);
DISPLAY 0.489362 (-5535 3685);
PAINT MONO (-5535 3685);
FORCEPROP 0 LASTPIN (-5525 3625) $PN BB63
J 2
(-5535 3635);
DISPLAY 0.489362 (-5535 3635);
PAINT MONO (-5535 3635);
FORCEPROP 0 LASTPIN (-5525 3575) $PN BB62
J 2
(-5535 3585);
DISPLAY 0.489362 (-5535 3585);
PAINT MONO (-5535 3585);
FORCEPROP 0 LASTPIN (-3925 2425) $PN AJ64
J 0
(-3915 2435);
DISPLAY 0.489362 (-3915 2435);
PAINT MONO (-3915 2435);
FORCEPROP 0 LASTPIN (-3925 2375) $PN AK62
J 0
(-3915 2385);
DISPLAY 0.489362 (-3915 2385);
PAINT MONO (-3915 2385);
FORCEPROP 0 LASTPIN (-3925 2325) $PN AK63
J 0
(-3915 2335);
DISPLAY 0.489362 (-3915 2335);
PAINT MONO (-3915 2335);
FORCEPROP 0 LASTPIN (-3925 2275) $PN AL62
J 0
(-3915 2285);
DISPLAY 0.489362 (-3915 2285);
PAINT MONO (-3915 2285);
FORCEPROP 0 LASTPIN (-3925 2225) $PN AN64
J 0
(-3915 2235);
DISPLAY 0.489362 (-3915 2235);
PAINT MONO (-3915 2235);
FORCEPROP 0 LASTPIN (-3925 2175) $PN AP62
J 0
(-3915 2185);
DISPLAY 0.489362 (-3915 2185);
PAINT MONO (-3915 2185);
FORCEPROP 0 LASTPIN (-3925 2125) $PN AP63
J 0
(-3915 2135);
DISPLAY 0.489362 (-3915 2135);
PAINT MONO (-3915 2135);
FORCEPROP 0 LASTPIN (-3925 2075) $PN AR62
J 0
(-3915 2085);
DISPLAY 0.489362 (-3915 2085);
PAINT MONO (-3915 2085);
FORCEPROP 0 LASTPIN (-3925 6025) $PN E64
J 0
(-3915 6035);
DISPLAY 0.489362 (-3915 6035);
PAINT MONO (-3915 6035);
FORCEPROP 0 LASTPIN (-3925 5975) $PN F62
J 0
(-3915 5985);
DISPLAY 0.489362 (-3915 5985);
PAINT MONO (-3915 5985);
FORCEPROP 0 LASTPIN (-3925 5925) $PN F63
J 0
(-3915 5935);
DISPLAY 0.489362 (-3915 5935);
PAINT MONO (-3915 5935);
FORCEPROP 0 LASTPIN (-3925 5875) $PN G62
J 0
(-3915 5885);
DISPLAY 0.489362 (-3915 5885);
PAINT MONO (-3915 5885);
FORCEPROP 0 LASTPIN (-3925 5825) $PN J64
J 0
(-3915 5835);
DISPLAY 0.489362 (-3915 5835);
PAINT MONO (-3915 5835);
FORCEPROP 0 LASTPIN (-3925 5775) $PN K62
J 0
(-3915 5785);
DISPLAY 0.489362 (-3915 5785);
PAINT MONO (-3915 5785);
FORCEPROP 0 LASTPIN (-3925 5725) $PN K63
J 0
(-3915 5735);
DISPLAY 0.489362 (-3915 5735);
PAINT MONO (-3915 5735);
FORCEPROP 0 LASTPIN (-3925 5675) $PN L62
J 0
(-3915 5685);
DISPLAY 0.489362 (-3915 5685);
PAINT MONO (-3915 5685);
FORCEPROP 0 LASTPIN (-3925 5575) $PN L64
J 0
(-3915 5585);
DISPLAY 0.489362 (-3915 5585);
PAINT MONO (-3915 5585);
FORCEPROP 0 LASTPIN (-3925 5525) $PN M62
J 0
(-3915 5535);
DISPLAY 0.489362 (-3915 5535);
PAINT MONO (-3915 5535);
FORCEPROP 0 LASTPIN (-3925 5475) $PN M63
J 0
(-3915 5485);
DISPLAY 0.489362 (-3915 5485);
PAINT MONO (-3915 5485);
FORCEPROP 0 LASTPIN (-3925 5425) $PN N62
J 0
(-3915 5435);
DISPLAY 0.489362 (-3915 5435);
PAINT MONO (-3915 5435);
FORCEPROP 0 LASTPIN (-3925 5375) $PN R64
J 0
(-3915 5385);
DISPLAY 0.489362 (-3915 5385);
PAINT MONO (-3915 5385);
FORCEPROP 0 LASTPIN (-3925 5325) $PN T62
J 0
(-3915 5335);
DISPLAY 0.489362 (-3915 5335);
PAINT MONO (-3915 5335);
FORCEPROP 0 LASTPIN (-3925 5275) $PN T63
J 0
(-3915 5285);
DISPLAY 0.489362 (-3915 5285);
PAINT MONO (-3915 5285);
FORCEPROP 0 LASTPIN (-3925 5225) $PN U62
J 0
(-3915 5235);
DISPLAY 0.489362 (-3915 5235);
PAINT MONO (-3915 5235);
FORCEPROP 0 LASTPIN (-3925 5125) $PN U64
J 0
(-3915 5135);
DISPLAY 0.489362 (-3915 5135);
PAINT MONO (-3915 5135);
FORCEPROP 0 LASTPIN (-3925 5075) $PN V62
J 0
(-3915 5085);
DISPLAY 0.489362 (-3915 5085);
PAINT MONO (-3915 5085);
FORCEPROP 0 LASTPIN (-3925 5025) $PN V63
J 0
(-3915 5035);
DISPLAY 0.489362 (-3915 5035);
PAINT MONO (-3915 5035);
FORCEPROP 0 LASTPIN (-3925 4975) $PN W62
J 0
(-3915 4985);
DISPLAY 0.489362 (-3915 4985);
PAINT MONO (-3915 4985);
FORCEPROP 0 LASTPIN (-3925 4925) $PN AA64
J 0
(-3915 4935);
DISPLAY 0.489362 (-3915 4935);
PAINT MONO (-3915 4935);
FORCEPROP 0 LASTPIN (-3925 4875) $PN AB62
J 0
(-3915 4885);
DISPLAY 0.489362 (-3915 4885);
PAINT MONO (-3915 4885);
FORCEPROP 0 LASTPIN (-3925 4825) $PN AB63
J 0
(-3915 4835);
DISPLAY 0.489362 (-3915 4835);
PAINT MONO (-3915 4835);
FORCEPROP 0 LASTPIN (-3925 4775) $PN AC62
J 0
(-3915 4785);
DISPLAY 0.489362 (-3915 4785);
PAINT MONO (-3915 4785);
FORCEPROP 0 LASTPIN (-3925 4675) $PN AC64
J 0
(-3915 4685);
DISPLAY 0.489362 (-3915 4685);
PAINT MONO (-3915 4685);
FORCEPROP 0 LASTPIN (-3925 4625) $PN AD62
J 0
(-3915 4635);
DISPLAY 0.489362 (-3915 4635);
PAINT MONO (-3915 4635);
FORCEPROP 0 LASTPIN (-3925 4575) $PN AD63
J 0
(-3915 4585);
DISPLAY 0.489362 (-3915 4585);
PAINT MONO (-3915 4585);
FORCEPROP 0 LASTPIN (-3925 4525) $PN AE62
J 0
(-3915 4535);
DISPLAY 0.489362 (-3915 4535);
PAINT MONO (-3915 4535);
FORCEPROP 0 LASTPIN (-3925 4475) $PN AG64
J 0
(-3915 4485);
DISPLAY 0.489362 (-3915 4485);
PAINT MONO (-3915 4485);
FORCEPROP 0 LASTPIN (-3925 4425) $PN AH62
J 0
(-3915 4435);
DISPLAY 0.489362 (-3915 4435);
PAINT MONO (-3915 4435);
FORCEPROP 0 LASTPIN (-3925 4375) $PN AH63
J 0
(-3915 4385);
DISPLAY 0.489362 (-3915 4385);
PAINT MONO (-3915 4385);
FORCEPROP 0 LASTPIN (-3925 4325) $PN AJ62
J 0
(-3915 4335);
DISPLAY 0.489362 (-3915 4335);
PAINT MONO (-3915 4335);
FORCEPROP 0 LASTPIN (-5525 6025) $PN G64
J 2
(-5535 6035);
DISPLAY 0.489362 (-5535 6035);
PAINT MONO (-5535 6035);
FORCEPROP 0 LASTPIN (-5525 5925) $PN N64
J 2
(-5535 5935);
DISPLAY 0.489362 (-5535 5935);
PAINT MONO (-5535 5935);
FORCEPROP 0 LASTPIN (-5525 5825) $PN W64
J 2
(-5535 5835);
DISPLAY 0.489362 (-5535 5835);
PAINT MONO (-5535 5835);
FORCEPROP 0 LASTPIN (-5525 5725) $PN AE64
J 2
(-5535 5735);
DISPLAY 0.489362 (-5535 5735);
PAINT MONO (-5535 5735);
FORCEPROP 0 LASTPIN (-5525 5625) $PN AL64
J 2
(-5535 5635);
DISPLAY 0.489362 (-5535 5635);
PAINT MONO (-5535 5635);
FORCEPROP 0 LASTPIN (-5525 5525) $PN J62
J 2
(-5535 5535);
DISPLAY 0.489362 (-5535 5535);
PAINT MONO (-5535 5535);
FORCEPROP 0 LASTPIN (-5525 5425) $PN R62
J 2
(-5535 5435);
DISPLAY 0.489362 (-5535 5435);
PAINT MONO (-5535 5435);
FORCEPROP 0 LASTPIN (-5525 5325) $PN AA62
J 2
(-5535 5335);
DISPLAY 0.489362 (-5535 5335);
PAINT MONO (-5535 5335);
FORCEPROP 0 LASTPIN (-5525 5225) $PN AG62
J 2
(-5535 5235);
DISPLAY 0.489362 (-5535 5235);
PAINT MONO (-5535 5235);
FORCEPROP 0 LASTPIN (-5525 5125) $PN AN62
J 2
(-5535 5135);
DISPLAY 0.489362 (-5535 5135);
PAINT MONO (-5535 5135);
FORCEPROP 0 LASTPIN (-5525 5975) $PN H63
J 2
(-5535 5985);
DISPLAY 0.489362 (-5535 5985);
PAINT MONO (-5535 5985);
FORCEPROP 0 LASTPIN (-5525 5875) $PN P63
J 2
(-5535 5885);
DISPLAY 0.489362 (-5535 5885);
PAINT MONO (-5535 5885);
FORCEPROP 0 LASTPIN (-5525 5775) $PN Y63
J 2
(-5535 5785);
DISPLAY 0.489362 (-5535 5785);
PAINT MONO (-5535 5785);
FORCEPROP 0 LASTPIN (-5525 5675) $PN AF63
J 2
(-5535 5685);
DISPLAY 0.489362 (-5535 5685);
PAINT MONO (-5535 5685);
FORCEPROP 0 LASTPIN (-5525 5575) $PN AM63
J 2
(-5535 5585);
DISPLAY 0.489362 (-5535 5585);
PAINT MONO (-5535 5585);
FORCEPROP 0 LASTPIN (-5525 5475) $PN H62
J 2
(-5535 5485);
DISPLAY 0.489362 (-5535 5485);
PAINT MONO (-5535 5485);
FORCEPROP 0 LASTPIN (-5525 5375) $PN P62
J 2
(-5535 5385);
DISPLAY 0.489362 (-5535 5385);
PAINT MONO (-5535 5385);
FORCEPROP 0 LASTPIN (-5525 5275) $PN Y62
J 2
(-5535 5285);
DISPLAY 0.489362 (-5535 5285);
PAINT MONO (-5535 5285);
FORCEPROP 0 LASTPIN (-5525 5175) $PN AF62
J 2
(-5535 5185);
DISPLAY 0.489362 (-5535 5185);
PAINT MONO (-5535 5185);
FORCEPROP 0 LASTPIN (-5525 5075) $PN AM62
J 2
(-5535 5085);
DISPLAY 0.489362 (-5535 5085);
PAINT MONO (-5535 5085);
FORCEPROP 0 LASTPIN (-5525 2625) $PN BC62
J 2
(-5535 2635);
DISPLAY 0.489362 (-5535 2635);
PAINT MONO (-5535 2635);
FORCEPROP 0 LASTPIN (-5525 2525) $PN BM62
J 2
(-5535 2535);
DISPLAY 0.489362 (-5535 2535);
PAINT MONO (-5535 2535);
FORCEPROP 0 LASTPIN (-5525 2475) $PN BN64
J 2
(-5535 2485);
DISPLAY 0.489362 (-5535 2485);
PAINT MONO (-5535 2485);
FORCEPROP 0 LASTPIN (-5525 2375) $PN BP63
J 2
(-5535 2385);
DISPLAY 0.489362 (-5535 2385);
PAINT MONO (-5535 2385);
FORCEPROP 0 LASTPIN (-5525 1475) $PN BL62
J 2
(-5535 1485);
DISPLAY 0.489362 (-5535 1485);
PAINT MONO (-5535 1485);
FORCEPROP 0 LASTPIN (-5525 1425) $PN BM63
J 2
(-5535 1435);
DISPLAY 0.489362 (-5535 1435);
PAINT MONO (-5535 1435);
FORCEPROP 0 LASTPIN (-5525 1325) $PN BR64
J 2
(-5535 1335);
DISPLAY 0.489362 (-5535 1335);
PAINT MONO (-5535 1335);
FORCEPROP 0 LASTPIN (-5525 3475) $PN BG62
J 2
(-5535 3485);
DISPLAY 0.489362 (-5535 3485);
PAINT MONO (-5535 3485);
FORCEPROP 0 LASTPIN (-5525 3425) $PN BH62
J 2
(-5535 3435);
DISPLAY 0.489362 (-5535 3435);
PAINT MONO (-5535 3435);
FORCEPROP 0 LASTPIN (-5525 3375) $PN BH63
J 2
(-5535 3385);
DISPLAY 0.489362 (-5535 3385);
PAINT MONO (-5535 3385);
FORCEPROP 0 LASTPIN (-5525 3325) $PN BJ64
J 2
(-5535 3335);
DISPLAY 0.489362 (-5535 3335);
PAINT MONO (-5535 3335);
FORCEPROP 0 LASTPIN (-5525 3275) $PN BJ62
J 2
(-5535 3285);
DISPLAY 0.489362 (-5535 3285);
PAINT MONO (-5535 3285);
FORCEPROP 0 LASTPIN (-5525 3225) $PN BK62
J 2
(-5535 3235);
DISPLAY 0.489362 (-5535 3235);
PAINT MONO (-5535 3235);
FORCEPROP 0 LASTPIN (-5525 3175) $PN BK63
J 2
(-5535 3185);
DISPLAY 0.489362 (-5535 3185);
PAINT MONO (-5535 3185);
FORCEPROP 0 LASTPIN (-3925 1975) $PN BY63
J 0
(-3915 1985);
DISPLAY 0.489362 (-3915 1985);
PAINT MONO (-3915 1985);
FORCEPROP 0 LASTPIN (-3925 1925) $PN CA62
J 0
(-3915 1935);
DISPLAY 0.489362 (-3915 1935);
PAINT MONO (-3915 1935);
FORCEPROP 0 LASTPIN (-3925 1875) $PN CA64
J 0
(-3915 1885);
DISPLAY 0.489362 (-3915 1885);
PAINT MONO (-3915 1885);
FORCEPROP 0 LASTPIN (-3925 1825) $PN CB62
J 0
(-3915 1835);
DISPLAY 0.489362 (-3915 1835);
PAINT MONO (-3915 1835);
FORCEPROP 0 LASTPIN (-3925 1775) $PN BT63
J 0
(-3915 1785);
DISPLAY 0.489362 (-3915 1785);
PAINT MONO (-3915 1785);
FORCEPROP 0 LASTPIN (-3925 1725) $PN BU62
J 0
(-3915 1735);
DISPLAY 0.489362 (-3915 1735);
PAINT MONO (-3915 1735);
FORCEPROP 0 LASTPIN (-3925 1675) $PN BU64
J 0
(-3915 1685);
DISPLAY 0.489362 (-3915 1685);
PAINT MONO (-3915 1685);
FORCEPROP 0 LASTPIN (-3925 1625) $PN BV62
J 0
(-3915 1635);
DISPLAY 0.489362 (-3915 1635);
PAINT MONO (-3915 1635);
FORCEPROP 0 LASTPIN (-3925 4225) $PN CB63
J 0
(-3915 4235);
DISPLAY 0.489362 (-3915 4235);
PAINT MONO (-3915 4235);
FORCEPROP 0 LASTPIN (-3925 4175) $PN CC62
J 0
(-3915 4185);
DISPLAY 0.489362 (-3915 4185);
PAINT MONO (-3915 4185);
FORCEPROP 0 LASTPIN (-3925 4125) $PN CC64
J 0
(-3915 4135);
DISPLAY 0.489362 (-3915 4135);
PAINT MONO (-3915 4135);
FORCEPROP 0 LASTPIN (-3925 4075) $PN CD62
J 0
(-3915 4085);
DISPLAY 0.489362 (-3915 4085);
PAINT MONO (-3915 4085);
FORCEPROP 0 LASTPIN (-3925 4025) $PN CF63
J 0
(-3915 4035);
DISPLAY 0.489362 (-3915 4035);
PAINT MONO (-3915 4035);
FORCEPROP 0 LASTPIN (-3925 3975) $PN CG62
J 0
(-3915 3985);
DISPLAY 0.489362 (-3915 3985);
PAINT MONO (-3915 3985);
FORCEPROP 0 LASTPIN (-3925 3925) $PN CG64
J 0
(-3915 3935);
DISPLAY 0.489362 (-3915 3935);
PAINT MONO (-3915 3935);
FORCEPROP 0 LASTPIN (-3925 3875) $PN CH62
J 0
(-3915 3885);
DISPLAY 0.489362 (-3915 3885);
PAINT MONO (-3915 3885);
FORCEPROP 0 LASTPIN (-3925 3775) $PN CH63
J 0
(-3915 3785);
DISPLAY 0.489362 (-3915 3785);
PAINT MONO (-3915 3785);
FORCEPROP 0 LASTPIN (-3925 3725) $PN CJ62
J 0
(-3915 3735);
DISPLAY 0.489362 (-3915 3735);
PAINT MONO (-3915 3735);
FORCEPROP 0 LASTPIN (-3925 3675) $PN CJ64
J 0
(-3915 3685);
DISPLAY 0.489362 (-3915 3685);
PAINT MONO (-3915 3685);
FORCEPROP 0 LASTPIN (-3925 3625) $PN CK62
J 0
(-3915 3635);
DISPLAY 0.489362 (-3915 3635);
PAINT MONO (-3915 3635);
FORCEPROP 0 LASTPIN (-3925 3575) $PN CM63
J 0
(-3915 3585);
DISPLAY 0.489362 (-3915 3585);
PAINT MONO (-3915 3585);
FORCEPROP 0 LASTPIN (-3925 3525) $PN CN62
J 0
(-3915 3535);
DISPLAY 0.489362 (-3915 3535);
PAINT MONO (-3915 3535);
FORCEPROP 0 LASTPIN (-3925 3475) $PN CN64
J 0
(-3915 3485);
DISPLAY 0.489362 (-3915 3485);
PAINT MONO (-3915 3485);
FORCEPROP 0 LASTPIN (-3925 3425) $PN CP62
J 0
(-3915 3435);
DISPLAY 0.489362 (-3915 3435);
PAINT MONO (-3915 3435);
FORCEPROP 0 LASTPIN (-3925 3325) $PN CP63
J 0
(-3915 3335);
DISPLAY 0.489362 (-3915 3335);
PAINT MONO (-3915 3335);
FORCEPROP 0 LASTPIN (-3925 3275) $PN CR62
J 0
(-3915 3285);
DISPLAY 0.489362 (-3915 3285);
PAINT MONO (-3915 3285);
FORCEPROP 0 LASTPIN (-3925 3225) $PN CR64
J 0
(-3915 3235);
DISPLAY 0.489362 (-3915 3235);
PAINT MONO (-3915 3235);
FORCEPROP 0 LASTPIN (-3925 3175) $PN CT62
J 0
(-3915 3185);
DISPLAY 0.489362 (-3915 3185);
PAINT MONO (-3915 3185);
FORCEPROP 0 LASTPIN (-3925 3125) $PN CV63
J 0
(-3915 3135);
DISPLAY 0.489362 (-3915 3135);
PAINT MONO (-3915 3135);
FORCEPROP 0 LASTPIN (-3925 3075) $PN CW62
J 0
(-3915 3085);
DISPLAY 0.489362 (-3915 3085);
PAINT MONO (-3915 3085);
FORCEPROP 0 LASTPIN (-3925 3025) $PN CW64
J 0
(-3915 3035);
DISPLAY 0.489362 (-3915 3035);
PAINT MONO (-3915 3035);
FORCEPROP 0 LASTPIN (-3925 2975) $PN CY62
J 0
(-3915 2985);
DISPLAY 0.489362 (-3915 2985);
PAINT MONO (-3915 2985);
FORCEPROP 0 LASTPIN (-3925 2875) $PN CY63
J 0
(-3915 2885);
DISPLAY 0.489362 (-3915 2885);
PAINT MONO (-3915 2885);
FORCEPROP 0 LASTPIN (-3925 2825) $PN DA62
J 0
(-3915 2835);
DISPLAY 0.489362 (-3915 2835);
PAINT MONO (-3915 2835);
FORCEPROP 0 LASTPIN (-3925 2775) $PN DA64
J 0
(-3915 2785);
DISPLAY 0.489362 (-3915 2785);
PAINT MONO (-3915 2785);
FORCEPROP 0 LASTPIN (-3925 2725) $PN DB62
J 0
(-3915 2735);
DISPLAY 0.489362 (-3915 2735);
PAINT MONO (-3915 2735);
FORCEPROP 0 LASTPIN (-3925 2675) $PN DD63
J 0
(-3915 2685);
DISPLAY 0.489362 (-3915 2685);
PAINT MONO (-3915 2685);
FORCEPROP 0 LASTPIN (-3925 2625) $PN DE62
J 0
(-3915 2635);
DISPLAY 0.489362 (-3915 2635);
PAINT MONO (-3915 2635);
FORCEPROP 0 LASTPIN (-3925 2575) $PN DE64
J 0
(-3915 2585);
DISPLAY 0.489362 (-3915 2585);
PAINT MONO (-3915 2585);
FORCEPROP 0 LASTPIN (-3925 2525) $PN DF62
J 0
(-3915 2535);
DISPLAY 0.489362 (-3915 2535);
PAINT MONO (-3915 2535);
FORCEPROP 0 LASTPIN (-5525 4975) $PN CD63
J 2
(-5535 4985);
DISPLAY 0.489362 (-5535 4985);
PAINT MONO (-5535 4985);
FORCEPROP 0 LASTPIN (-5525 4875) $PN CK63
J 2
(-5535 4885);
DISPLAY 0.489362 (-5535 4885);
PAINT MONO (-5535 4885);
FORCEPROP 0 LASTPIN (-5525 4775) $PN CT63
J 2
(-5535 4785);
DISPLAY 0.489362 (-5535 4785);
PAINT MONO (-5535 4785);
FORCEPROP 0 LASTPIN (-5525 4675) $PN DB63
J 2
(-5535 4685);
DISPLAY 0.489362 (-5535 4685);
PAINT MONO (-5535 4685);
FORCEPROP 0 LASTPIN (-5525 4575) $PN BY62
J 2
(-5535 4585);
DISPLAY 0.489362 (-5535 4585);
PAINT MONO (-5535 4585);
FORCEPROP 0 LASTPIN (-5525 4475) $PN CF62
J 2
(-5535 4485);
DISPLAY 0.489362 (-5535 4485);
PAINT MONO (-5535 4485);
FORCEPROP 0 LASTPIN (-5525 4375) $PN CM62
J 2
(-5535 4385);
DISPLAY 0.489362 (-5535 4385);
PAINT MONO (-5535 4385);
FORCEPROP 0 LASTPIN (-5525 4275) $PN CV62
J 2
(-5535 4285);
DISPLAY 0.489362 (-5535 4285);
PAINT MONO (-5535 4285);
FORCEPROP 0 LASTPIN (-5525 4175) $PN DD62
J 2
(-5535 4185);
DISPLAY 0.489362 (-5535 4185);
PAINT MONO (-5535 4185);
FORCEPROP 0 LASTPIN (-5525 4075) $PN BV63
J 2
(-5535 4085);
DISPLAY 0.489362 (-5535 4085);
PAINT MONO (-5535 4085);
FORCEPROP 0 LASTPIN (-5525 4925) $PN CE64
J 2
(-5535 4935);
DISPLAY 0.489362 (-5535 4935);
PAINT MONO (-5535 4935);
FORCEPROP 0 LASTPIN (-5525 4825) $PN CL64
J 2
(-5535 4835);
DISPLAY 0.489362 (-5535 4835);
PAINT MONO (-5535 4835);
FORCEPROP 0 LASTPIN (-5525 4725) $PN CU64
J 2
(-5535 4735);
DISPLAY 0.489362 (-5535 4735);
PAINT MONO (-5535 4735);
FORCEPROP 0 LASTPIN (-5525 4625) $PN DC64
J 2
(-5535 4635);
DISPLAY 0.489362 (-5535 4635);
PAINT MONO (-5535 4635);
FORCEPROP 0 LASTPIN (-5525 4525) $PN BW62
J 2
(-5535 4535);
DISPLAY 0.489362 (-5535 4535);
PAINT MONO (-5535 4535);
FORCEPROP 0 LASTPIN (-5525 4425) $PN CE62
J 2
(-5535 4435);
DISPLAY 0.489362 (-5535 4435);
PAINT MONO (-5535 4435);
FORCEPROP 0 LASTPIN (-5525 4325) $PN CL62
J 2
(-5535 4335);
DISPLAY 0.489362 (-5535 4335);
PAINT MONO (-5535 4335);
FORCEPROP 0 LASTPIN (-5525 4225) $PN CU62
J 2
(-5535 4235);
DISPLAY 0.489362 (-5535 4235);
PAINT MONO (-5535 4235);
FORCEPROP 0 LASTPIN (-5525 4125) $PN DC62
J 2
(-5535 4135);
DISPLAY 0.489362 (-5535 4135);
PAINT MONO (-5535 4135);
FORCEPROP 0 LASTPIN (-5525 4025) $PN BW64
J 2
(-5535 4035);
DISPLAY 0.489362 (-5535 4035);
PAINT MONO (-5535 4035);
FORCEPROP 0 LASTPIN (-5525 2275) $PN BL64
J 2
(-5535 2285);
DISPLAY 0.489362 (-5535 2285);
PAINT MONO (-5535 2285);
FORCEPROP 0 LASTPIN (-5525 1225) $PN BF62
J 2
(-5535 1235);
DISPLAY 0.489362 (-5535 1235);
PAINT MONO (-5535 1235);
FORCEPROP 2 LAST PART_TYPE SMLF
J 0
(-5375 6375);
DISPLAY 1.021277 (-5375 6375);
FORCEPROP 1 LAST MATERIAL IO
J 0
(-5370 6207);
DISPLAY 0.489362 (-5370 6207);
PAINT SKYBLUE (-5370 6207);
FORCEPROP 2 LAST VALUE SOCKET6096_13568-001
J 0
(-5375 6275);
DISPLAY 0.489362 (-5375 6275);
PAINT SKYBLUE (-5375 6275);
FORCEPROP 1 LAST PART_NUMBER DGA^6000030
J 0
(-5370 6334);
DISPLAY 0.489362 (-5370 6334);
PAINT SKYBLUE (-5370 6334);
FORCEPROP 2 LAST CDS_LIB pure_quanta
J 0
(-4725 3625);
DISPLAY INVISIBLE (-4725 3625);
FORCEPROP 1 LAST NEEDS_NO_SIZE TRUE
J 0
(-4725 3625);
DISPLAY 0.723404 (-4725 3625);
PAINT GREEN (-4725 3625);
DISPLAY INVISIBLE (-4725 3625);
FORCEPROP 1 LAST CDS_LMAN_SYM_OUTLINE -650,2550,650,-2550
J 0
(-4725 3625);
DISPLAY 0.468085 (-4725 3625);
PAINT GREEN (-4725 3625);
DISPLAY INVISIBLE (-4725 3625);
FORCEPROP 1 LAST PATH I159
J 0
(-4725 3625);
DISPLAY 0.723404 (-4725 3625);
PAINT GREEN (-4725 3625);
DISPLAY INVISIBLE (-4725 3625);
FORCEADD OFFPAGE..3
(-2725 6050);
FORCEPROP 2 LAST $XR0 98 
J 0
(-2511 6050);
DISPLAY 0.638298 (-2511 6050);
PAINT MONO (-2511 6050);
FORCEPROP 2 LAST PATH I160
J 0
(-2500 6100);
DISPLAY 1.021277 (-2500 6100);
DISPLAY INVISIBLE (-2500 6100);
FORCEPROP 1 LAST COMMENT_BODY TRUE
J 0
(-2775 5950);
DISPLAY 0.872340 (-2775 5950);
PAINT GREEN (-2775 5950);
DISPLAY INVISIBLE (-2775 5950);
FORCEPROP 1 LAST OFFPAGE TRUE
J 0
(-2400 5925);
DISPLAY 0.872340 (-2400 5925);
PAINT GREEN (-2400 5925);
DISPLAY INVISIBLE (-2400 5925);
FORCEPROP 2 LAST CDS_LIB mstr_standard
J 0
(-2725 6050);
DISPLAY 0.723404 (-2725 6050);
PAINT MONO (-2725 6050);
DISPLAY INVISIBLE (-2725 6050);
FORCEADD OFFPAGE..3
(-2725 4250);
FORCEPROP 2 LAST $XR0 98 
J 0
(-2511 4250);
DISPLAY 0.638298 (-2511 4250);
PAINT MONO (-2511 4250);
FORCEPROP 2 LAST PATH I161
J 0
(-2500 4300);
DISPLAY 1.021277 (-2500 4300);
DISPLAY INVISIBLE (-2500 4300);
FORCEPROP 1 LAST COMMENT_BODY TRUE
J 0
(-2775 4150);
DISPLAY 0.872340 (-2775 4150);
PAINT GREEN (-2775 4150);
DISPLAY INVISIBLE (-2775 4150);
FORCEPROP 1 LAST OFFPAGE TRUE
J 0
(-2400 4125);
DISPLAY 0.872340 (-2400 4125);
PAINT GREEN (-2400 4125);
DISPLAY INVISIBLE (-2400 4125);
FORCEPROP 2 LAST CDS_LIB mstr_standard
J 0
(-2725 4250);
DISPLAY 0.723404 (-2725 4250);
PAINT MONO (-2725 4250);
DISPLAY INVISIBLE (-2725 4250);
FORCEADD TAP..1
(-3450 5925);
FORCEPROP 3 LASTPIN (-3500 5925) SIG_NAME M_B_CPU1_SA_DQ<2>
J 0
(-3490 5935);
DISPLAY 0.659574 (-3490 5935);
PAINT MONO (-3490 5935);
DISPLAY INVISIBLE (-3490 5935);
FORCEPROP 1 LASTPIN (-3500 5925) BN 2
J 0
(-3512 5933);
DISPLAY 0.489362 (-3512 5933);
PAINT GREEN (-3512 5933);
FORCEPROP 2 LAST CDS_LIB mstr_standard
J 0
(-3450 5925);
DISPLAY 0.723404 (-3450 5925);
PAINT MONO (-3450 5925);
DISPLAY INVISIBLE (-3450 5925);
FORCEPROP 1 LAST BODY_TYPE PLUMBING
J 0
(-3450 5975);
DISPLAY 0.872340 (-3450 5975);
PAINT GREEN (-3450 5975);
DISPLAY INVISIBLE (-3450 5975);
FORCEPROP 1 LAST HDL_TAP TRUE
J 0
(-3125 5800);
DISPLAY 0.872340 (-3125 5800);
DISPLAY INVISIBLE (-3125 5800);
FORCEPROP 1 LAST PATH I162
J 0
(-3452 5925);
DISPLAY 0.872340 (-3452 5925);
PAINT GREEN (-3452 5925);
DISPLAY INVISIBLE (-3452 5925);
FORCEADD TAP..1
(-3450 5975);
FORCEPROP 3 LASTPIN (-3500 5975) SIG_NAME M_B_CPU1_SA_DQ<1>
J 0
(-3490 5985);
DISPLAY 0.659574 (-3490 5985);
PAINT MONO (-3490 5985);
DISPLAY INVISIBLE (-3490 5985);
FORCEPROP 1 LASTPIN (-3500 5975) BN 1
J 0
(-3512 5983);
DISPLAY 0.489362 (-3512 5983);
PAINT GREEN (-3512 5983);
FORCEPROP 2 LAST CDS_LIB mstr_standard
J 0
(-3450 5975);
DISPLAY 0.723404 (-3450 5975);
PAINT MONO (-3450 5975);
DISPLAY INVISIBLE (-3450 5975);
FORCEPROP 1 LAST BODY_TYPE PLUMBING
J 0
(-3450 6025);
DISPLAY 0.872340 (-3450 6025);
PAINT GREEN (-3450 6025);
DISPLAY INVISIBLE (-3450 6025);
FORCEPROP 1 LAST HDL_TAP TRUE
J 0
(-3125 5850);
DISPLAY 0.872340 (-3125 5850);
DISPLAY INVISIBLE (-3125 5850);
FORCEPROP 1 LAST PATH I163
J 0
(-3452 5975);
DISPLAY 0.872340 (-3452 5975);
PAINT GREEN (-3452 5975);
DISPLAY INVISIBLE (-3452 5975);
FORCEADD TAP..1
(-3450 6025);
FORCEPROP 3 LASTPIN (-3500 6025) SIG_NAME M_B_CPU1_SA_DQ<0>
J 0
(-3490 6035);
DISPLAY 0.659574 (-3490 6035);
PAINT MONO (-3490 6035);
DISPLAY INVISIBLE (-3490 6035);
FORCEPROP 1 LASTPIN (-3500 6025) BN 0
J 0
(-3512 6033);
DISPLAY 0.489362 (-3512 6033);
PAINT GREEN (-3512 6033);
FORCEPROP 2 LAST CDS_LIB mstr_standard
J 0
(-3450 6025);
DISPLAY 0.723404 (-3450 6025);
PAINT MONO (-3450 6025);
DISPLAY INVISIBLE (-3450 6025);
FORCEPROP 1 LAST BODY_TYPE PLUMBING
J 0
(-3450 6075);
DISPLAY 0.872340 (-3450 6075);
PAINT GREEN (-3450 6075);
DISPLAY INVISIBLE (-3450 6075);
FORCEPROP 1 LAST HDL_TAP TRUE
J 0
(-3125 5900);
DISPLAY 0.872340 (-3125 5900);
DISPLAY INVISIBLE (-3125 5900);
FORCEPROP 1 LAST PATH I164
J 0
(-3452 6025);
DISPLAY 0.872340 (-3452 6025);
PAINT GREEN (-3452 6025);
DISPLAY INVISIBLE (-3452 6025);
FORCEADD TAP..1
(-3450 5825);
FORCEPROP 3 LASTPIN (-3500 5825) SIG_NAME M_B_CPU1_SA_DQ<4>
J 0
(-3490 5835);
DISPLAY 0.659574 (-3490 5835);
PAINT MONO (-3490 5835);
DISPLAY INVISIBLE (-3490 5835);
FORCEPROP 1 LASTPIN (-3500 5825) BN 4
J 0
(-3512 5833);
DISPLAY 0.489362 (-3512 5833);
PAINT GREEN (-3512 5833);
FORCEPROP 2 LAST CDS_LIB mstr_standard
J 0
(-3450 5825);
DISPLAY 0.723404 (-3450 5825);
PAINT MONO (-3450 5825);
DISPLAY INVISIBLE (-3450 5825);
FORCEPROP 1 LAST BODY_TYPE PLUMBING
J 0
(-3450 5875);
DISPLAY 0.872340 (-3450 5875);
PAINT GREEN (-3450 5875);
DISPLAY INVISIBLE (-3450 5875);
FORCEPROP 1 LAST HDL_TAP TRUE
J 0
(-3125 5700);
DISPLAY 0.872340 (-3125 5700);
DISPLAY INVISIBLE (-3125 5700);
FORCEPROP 1 LAST PATH I165
J 0
(-3452 5825);
DISPLAY 0.872340 (-3452 5825);
PAINT GREEN (-3452 5825);
DISPLAY INVISIBLE (-3452 5825);
FORCEADD TAP..1
(-3450 5875);
FORCEPROP 3 LASTPIN (-3500 5875) SIG_NAME M_B_CPU1_SA_DQ<3>
J 0
(-3490 5885);
DISPLAY 0.659574 (-3490 5885);
PAINT MONO (-3490 5885);
DISPLAY INVISIBLE (-3490 5885);
FORCEPROP 1 LASTPIN (-3500 5875) BN 3
J 0
(-3512 5883);
DISPLAY 0.489362 (-3512 5883);
PAINT GREEN (-3512 5883);
FORCEPROP 2 LAST CDS_LIB mstr_standard
J 0
(-3450 5875);
DISPLAY 0.723404 (-3450 5875);
PAINT MONO (-3450 5875);
DISPLAY INVISIBLE (-3450 5875);
FORCEPROP 1 LAST BODY_TYPE PLUMBING
J 0
(-3450 5925);
DISPLAY 0.872340 (-3450 5925);
PAINT GREEN (-3450 5925);
DISPLAY INVISIBLE (-3450 5925);
FORCEPROP 1 LAST HDL_TAP TRUE
J 0
(-3125 5750);
DISPLAY 0.872340 (-3125 5750);
DISPLAY INVISIBLE (-3125 5750);
FORCEPROP 1 LAST PATH I166
J 0
(-3452 5875);
DISPLAY 0.872340 (-3452 5875);
PAINT GREEN (-3452 5875);
DISPLAY INVISIBLE (-3452 5875);
FORCEADD TAP..1
(-3450 5775);
FORCEPROP 3 LASTPIN (-3500 5775) SIG_NAME M_B_CPU1_SA_DQ<5>
J 0
(-3490 5785);
DISPLAY 0.659574 (-3490 5785);
PAINT MONO (-3490 5785);
DISPLAY INVISIBLE (-3490 5785);
FORCEPROP 1 LASTPIN (-3500 5775) BN 5
J 0
(-3512 5783);
DISPLAY 0.489362 (-3512 5783);
PAINT GREEN (-3512 5783);
FORCEPROP 2 LAST CDS_LIB mstr_standard
J 0
(-3450 5775);
DISPLAY 0.723404 (-3450 5775);
PAINT MONO (-3450 5775);
DISPLAY INVISIBLE (-3450 5775);
FORCEPROP 1 LAST BODY_TYPE PLUMBING
J 0
(-3450 5825);
DISPLAY 0.872340 (-3450 5825);
PAINT GREEN (-3450 5825);
DISPLAY INVISIBLE (-3450 5825);
FORCEPROP 1 LAST HDL_TAP TRUE
J 0
(-3125 5650);
DISPLAY 0.872340 (-3125 5650);
DISPLAY INVISIBLE (-3125 5650);
FORCEPROP 1 LAST PATH I167
J 0
(-3452 5775);
DISPLAY 0.872340 (-3452 5775);
PAINT GREEN (-3452 5775);
DISPLAY INVISIBLE (-3452 5775);
FORCEADD TAP..1
(-3450 5725);
FORCEPROP 3 LASTPIN (-3500 5725) SIG_NAME M_B_CPU1_SA_DQ<6>
J 0
(-3490 5735);
DISPLAY 0.659574 (-3490 5735);
PAINT MONO (-3490 5735);
DISPLAY INVISIBLE (-3490 5735);
FORCEPROP 1 LASTPIN (-3500 5725) BN 6
J 0
(-3512 5733);
DISPLAY 0.489362 (-3512 5733);
PAINT GREEN (-3512 5733);
FORCEPROP 2 LAST CDS_LIB mstr_standard
J 0
(-3450 5725);
DISPLAY 0.723404 (-3450 5725);
PAINT MONO (-3450 5725);
DISPLAY INVISIBLE (-3450 5725);
FORCEPROP 1 LAST BODY_TYPE PLUMBING
J 0
(-3450 5775);
DISPLAY 0.872340 (-3450 5775);
PAINT GREEN (-3450 5775);
DISPLAY INVISIBLE (-3450 5775);
FORCEPROP 1 LAST HDL_TAP TRUE
J 0
(-3125 5600);
DISPLAY 0.872340 (-3125 5600);
DISPLAY INVISIBLE (-3125 5600);
FORCEPROP 1 LAST PATH I168
J 0
(-3452 5725);
DISPLAY 0.872340 (-3452 5725);
PAINT GREEN (-3452 5725);
DISPLAY INVISIBLE (-3452 5725);
FORCEADD TAP..1
(-3450 5675);
FORCEPROP 3 LASTPIN (-3500 5675) SIG_NAME M_B_CPU1_SA_DQ<7>
J 0
(-3490 5685);
DISPLAY 0.659574 (-3490 5685);
PAINT MONO (-3490 5685);
DISPLAY INVISIBLE (-3490 5685);
FORCEPROP 1 LASTPIN (-3500 5675) BN 7
J 0
(-3512 5683);
DISPLAY 0.489362 (-3512 5683);
PAINT GREEN (-3512 5683);
FORCEPROP 2 LAST CDS_LIB mstr_standard
J 0
(-3450 5675);
DISPLAY 0.723404 (-3450 5675);
PAINT MONO (-3450 5675);
DISPLAY INVISIBLE (-3450 5675);
FORCEPROP 1 LAST BODY_TYPE PLUMBING
J 0
(-3450 5725);
DISPLAY 0.872340 (-3450 5725);
PAINT GREEN (-3450 5725);
DISPLAY INVISIBLE (-3450 5725);
FORCEPROP 1 LAST HDL_TAP TRUE
J 0
(-3125 5550);
DISPLAY 0.872340 (-3125 5550);
DISPLAY INVISIBLE (-3125 5550);
FORCEPROP 1 LAST PATH I169
J 0
(-3452 5675);
DISPLAY 0.872340 (-3452 5675);
PAINT GREEN (-3452 5675);
DISPLAY INVISIBLE (-3452 5675);
FORCEADD TAP..1
(-3450 5575);
FORCEPROP 3 LASTPIN (-3500 5575) SIG_NAME M_B_CPU1_SA_DQ<8>
J 0
(-3490 5585);
DISPLAY 0.659574 (-3490 5585);
PAINT MONO (-3490 5585);
DISPLAY INVISIBLE (-3490 5585);
FORCEPROP 1 LASTPIN (-3500 5575) BN 8
J 0
(-3512 5583);
DISPLAY 0.489362 (-3512 5583);
PAINT GREEN (-3512 5583);
FORCEPROP 2 LAST CDS_LIB mstr_standard
J 0
(-3450 5575);
DISPLAY 0.723404 (-3450 5575);
PAINT MONO (-3450 5575);
DISPLAY INVISIBLE (-3450 5575);
FORCEPROP 1 LAST BODY_TYPE PLUMBING
J 0
(-3450 5625);
DISPLAY 0.872340 (-3450 5625);
PAINT GREEN (-3450 5625);
DISPLAY INVISIBLE (-3450 5625);
FORCEPROP 1 LAST HDL_TAP TRUE
J 0
(-3125 5450);
DISPLAY 0.872340 (-3125 5450);
DISPLAY INVISIBLE (-3125 5450);
FORCEPROP 1 LAST PATH I170
J 0
(-3452 5575);
DISPLAY 0.872340 (-3452 5575);
PAINT GREEN (-3452 5575);
DISPLAY INVISIBLE (-3452 5575);
FORCEADD TAP..1
(-3450 5425);
FORCEPROP 3 LASTPIN (-3500 5425) SIG_NAME M_B_CPU1_SA_DQ<11>
J 0
(-3490 5435);
DISPLAY 0.659574 (-3490 5435);
PAINT MONO (-3490 5435);
DISPLAY INVISIBLE (-3490 5435);
FORCEPROP 1 LASTPIN (-3500 5425) BN 11
J 0
(-3512 5433);
DISPLAY 0.489362 (-3512 5433);
PAINT GREEN (-3512 5433);
FORCEPROP 2 LAST CDS_LIB mstr_standard
J 0
(-3450 5425);
DISPLAY 0.723404 (-3450 5425);
PAINT MONO (-3450 5425);
DISPLAY INVISIBLE (-3450 5425);
FORCEPROP 1 LAST BODY_TYPE PLUMBING
J 0
(-3450 5475);
DISPLAY 0.872340 (-3450 5475);
PAINT GREEN (-3450 5475);
DISPLAY INVISIBLE (-3450 5475);
FORCEPROP 1 LAST HDL_TAP TRUE
J 0
(-3125 5300);
DISPLAY 0.872340 (-3125 5300);
DISPLAY INVISIBLE (-3125 5300);
FORCEPROP 1 LAST PATH I171
J 0
(-3452 5425);
DISPLAY 0.872340 (-3452 5425);
PAINT GREEN (-3452 5425);
DISPLAY INVISIBLE (-3452 5425);
FORCEADD TAP..1
(-3450 5475);
FORCEPROP 3 LASTPIN (-3500 5475) SIG_NAME M_B_CPU1_SA_DQ<10>
J 0
(-3490 5485);
DISPLAY 0.659574 (-3490 5485);
PAINT MONO (-3490 5485);
DISPLAY INVISIBLE (-3490 5485);
FORCEPROP 1 LASTPIN (-3500 5475) BN 10
J 0
(-3512 5483);
DISPLAY 0.489362 (-3512 5483);
PAINT GREEN (-3512 5483);
FORCEPROP 2 LAST CDS_LIB mstr_standard
J 0
(-3450 5475);
DISPLAY 0.723404 (-3450 5475);
PAINT MONO (-3450 5475);
DISPLAY INVISIBLE (-3450 5475);
FORCEPROP 1 LAST BODY_TYPE PLUMBING
J 0
(-3450 5525);
DISPLAY 0.872340 (-3450 5525);
PAINT GREEN (-3450 5525);
DISPLAY INVISIBLE (-3450 5525);
FORCEPROP 1 LAST HDL_TAP TRUE
J 0
(-3125 5350);
DISPLAY 0.872340 (-3125 5350);
DISPLAY INVISIBLE (-3125 5350);
FORCEPROP 1 LAST PATH I172
J 0
(-3452 5475);
DISPLAY 0.872340 (-3452 5475);
PAINT GREEN (-3452 5475);
DISPLAY INVISIBLE (-3452 5475);
FORCEADD TAP..1
(-3450 5525);
FORCEPROP 3 LASTPIN (-3500 5525) SIG_NAME M_B_CPU1_SA_DQ<9>
J 0
(-3490 5535);
DISPLAY 0.659574 (-3490 5535);
PAINT MONO (-3490 5535);
DISPLAY INVISIBLE (-3490 5535);
FORCEPROP 1 LASTPIN (-3500 5525) BN 9
J 0
(-3512 5533);
DISPLAY 0.489362 (-3512 5533);
PAINT GREEN (-3512 5533);
FORCEPROP 2 LAST CDS_LIB mstr_standard
J 0
(-3450 5525);
DISPLAY 0.723404 (-3450 5525);
PAINT MONO (-3450 5525);
DISPLAY INVISIBLE (-3450 5525);
FORCEPROP 1 LAST BODY_TYPE PLUMBING
J 0
(-3450 5575);
DISPLAY 0.872340 (-3450 5575);
PAINT GREEN (-3450 5575);
DISPLAY INVISIBLE (-3450 5575);
FORCEPROP 1 LAST HDL_TAP TRUE
J 0
(-3125 5400);
DISPLAY 0.872340 (-3125 5400);
DISPLAY INVISIBLE (-3125 5400);
FORCEPROP 1 LAST PATH I173
J 0
(-3452 5525);
DISPLAY 0.872340 (-3452 5525);
PAINT GREEN (-3452 5525);
DISPLAY INVISIBLE (-3452 5525);
FORCEADD TAP..1
(-3450 5375);
FORCEPROP 3 LASTPIN (-3500 5375) SIG_NAME M_B_CPU1_SA_DQ<12>
J 0
(-3490 5385);
DISPLAY 0.659574 (-3490 5385);
PAINT MONO (-3490 5385);
DISPLAY INVISIBLE (-3490 5385);
FORCEPROP 1 LASTPIN (-3500 5375) BN 12
J 0
(-3512 5383);
DISPLAY 0.489362 (-3512 5383);
PAINT GREEN (-3512 5383);
FORCEPROP 2 LAST CDS_LIB mstr_standard
J 0
(-3450 5375);
DISPLAY 0.723404 (-3450 5375);
PAINT MONO (-3450 5375);
DISPLAY INVISIBLE (-3450 5375);
FORCEPROP 1 LAST BODY_TYPE PLUMBING
J 0
(-3450 5425);
DISPLAY 0.872340 (-3450 5425);
PAINT GREEN (-3450 5425);
DISPLAY INVISIBLE (-3450 5425);
FORCEPROP 1 LAST HDL_TAP TRUE
J 0
(-3125 5250);
DISPLAY 0.872340 (-3125 5250);
DISPLAY INVISIBLE (-3125 5250);
FORCEPROP 1 LAST PATH I174
J 0
(-3452 5375);
DISPLAY 0.872340 (-3452 5375);
PAINT GREEN (-3452 5375);
DISPLAY INVISIBLE (-3452 5375);
FORCEADD TAP..1
(-3450 5325);
FORCEPROP 3 LASTPIN (-3500 5325) SIG_NAME M_B_CPU1_SA_DQ<13>
J 0
(-3490 5335);
DISPLAY 0.659574 (-3490 5335);
PAINT MONO (-3490 5335);
DISPLAY INVISIBLE (-3490 5335);
FORCEPROP 1 LASTPIN (-3500 5325) BN 13
J 0
(-3512 5333);
DISPLAY 0.489362 (-3512 5333);
PAINT GREEN (-3512 5333);
FORCEPROP 2 LAST CDS_LIB mstr_standard
J 0
(-3450 5325);
DISPLAY 0.723404 (-3450 5325);
PAINT MONO (-3450 5325);
DISPLAY INVISIBLE (-3450 5325);
FORCEPROP 1 LAST BODY_TYPE PLUMBING
J 0
(-3450 5375);
DISPLAY 0.872340 (-3450 5375);
PAINT GREEN (-3450 5375);
DISPLAY INVISIBLE (-3450 5375);
FORCEPROP 1 LAST HDL_TAP TRUE
J 0
(-3125 5200);
DISPLAY 0.872340 (-3125 5200);
DISPLAY INVISIBLE (-3125 5200);
FORCEPROP 1 LAST PATH I175
J 0
(-3452 5325);
DISPLAY 0.872340 (-3452 5325);
PAINT GREEN (-3452 5325);
DISPLAY INVISIBLE (-3452 5325);
FORCEADD TAP..1
(-3450 5275);
FORCEPROP 3 LASTPIN (-3500 5275) SIG_NAME M_B_CPU1_SA_DQ<14>
J 0
(-3490 5285);
DISPLAY 0.659574 (-3490 5285);
PAINT MONO (-3490 5285);
DISPLAY INVISIBLE (-3490 5285);
FORCEPROP 1 LASTPIN (-3500 5275) BN 14
J 0
(-3512 5283);
DISPLAY 0.489362 (-3512 5283);
PAINT GREEN (-3512 5283);
FORCEPROP 2 LAST CDS_LIB mstr_standard
J 0
(-3450 5275);
DISPLAY 0.723404 (-3450 5275);
PAINT MONO (-3450 5275);
DISPLAY INVISIBLE (-3450 5275);
FORCEPROP 1 LAST BODY_TYPE PLUMBING
J 0
(-3450 5325);
DISPLAY 0.872340 (-3450 5325);
PAINT GREEN (-3450 5325);
DISPLAY INVISIBLE (-3450 5325);
FORCEPROP 1 LAST HDL_TAP TRUE
J 0
(-3125 5150);
DISPLAY 0.872340 (-3125 5150);
DISPLAY INVISIBLE (-3125 5150);
FORCEPROP 1 LAST PATH I176
J 0
(-3452 5275);
DISPLAY 0.872340 (-3452 5275);
PAINT GREEN (-3452 5275);
DISPLAY INVISIBLE (-3452 5275);
FORCEADD TAP..1
(-3450 5225);
FORCEPROP 3 LASTPIN (-3500 5225) SIG_NAME M_B_CPU1_SA_DQ<15>
J 0
(-3490 5235);
DISPLAY 0.659574 (-3490 5235);
PAINT MONO (-3490 5235);
DISPLAY INVISIBLE (-3490 5235);
FORCEPROP 1 LASTPIN (-3500 5225) BN 15
J 0
(-3512 5233);
DISPLAY 0.489362 (-3512 5233);
PAINT GREEN (-3512 5233);
FORCEPROP 2 LAST CDS_LIB mstr_standard
J 0
(-3450 5225);
DISPLAY 0.723404 (-3450 5225);
PAINT MONO (-3450 5225);
DISPLAY INVISIBLE (-3450 5225);
FORCEPROP 1 LAST BODY_TYPE PLUMBING
J 0
(-3450 5275);
DISPLAY 0.872340 (-3450 5275);
PAINT GREEN (-3450 5275);
DISPLAY INVISIBLE (-3450 5275);
FORCEPROP 1 LAST HDL_TAP TRUE
J 0
(-3125 5100);
DISPLAY 0.872340 (-3125 5100);
DISPLAY INVISIBLE (-3125 5100);
FORCEPROP 1 LAST PATH I177
J 0
(-3452 5225);
DISPLAY 0.872340 (-3452 5225);
PAINT GREEN (-3452 5225);
DISPLAY INVISIBLE (-3452 5225);
FORCEADD TAP..1
(-3450 5125);
FORCEPROP 3 LASTPIN (-3500 5125) SIG_NAME M_B_CPU1_SA_DQ<16>
J 0
(-3490 5135);
DISPLAY 0.659574 (-3490 5135);
PAINT MONO (-3490 5135);
DISPLAY INVISIBLE (-3490 5135);
FORCEPROP 1 LASTPIN (-3500 5125) BN 16
J 0
(-3512 5133);
DISPLAY 0.489362 (-3512 5133);
PAINT GREEN (-3512 5133);
FORCEPROP 2 LAST CDS_LIB mstr_standard
J 0
(-3450 5125);
DISPLAY 0.723404 (-3450 5125);
PAINT MONO (-3450 5125);
DISPLAY INVISIBLE (-3450 5125);
FORCEPROP 1 LAST BODY_TYPE PLUMBING
J 0
(-3450 5175);
DISPLAY 0.872340 (-3450 5175);
PAINT GREEN (-3450 5175);
DISPLAY INVISIBLE (-3450 5175);
FORCEPROP 1 LAST HDL_TAP TRUE
J 0
(-3125 5000);
DISPLAY 0.872340 (-3125 5000);
DISPLAY INVISIBLE (-3125 5000);
FORCEPROP 1 LAST PATH I178
J 0
(-3452 5125);
DISPLAY 0.872340 (-3452 5125);
PAINT GREEN (-3452 5125);
DISPLAY INVISIBLE (-3452 5125);
FORCEADD TAP..1
(-3450 5075);
FORCEPROP 3 LASTPIN (-3500 5075) SIG_NAME M_B_CPU1_SA_DQ<17>
J 0
(-3490 5085);
DISPLAY 0.659574 (-3490 5085);
PAINT MONO (-3490 5085);
DISPLAY INVISIBLE (-3490 5085);
FORCEPROP 1 LASTPIN (-3500 5075) BN 17
J 0
(-3512 5083);
DISPLAY 0.489362 (-3512 5083);
PAINT GREEN (-3512 5083);
FORCEPROP 2 LAST CDS_LIB mstr_standard
J 0
(-3450 5075);
DISPLAY 0.723404 (-3450 5075);
PAINT MONO (-3450 5075);
DISPLAY INVISIBLE (-3450 5075);
FORCEPROP 1 LAST BODY_TYPE PLUMBING
J 0
(-3450 5125);
DISPLAY 0.872340 (-3450 5125);
PAINT GREEN (-3450 5125);
DISPLAY INVISIBLE (-3450 5125);
FORCEPROP 1 LAST HDL_TAP TRUE
J 0
(-3125 4950);
DISPLAY 0.872340 (-3125 4950);
DISPLAY INVISIBLE (-3125 4950);
FORCEPROP 1 LAST PATH I179
J 0
(-3452 5075);
DISPLAY 0.872340 (-3452 5075);
PAINT GREEN (-3452 5075);
DISPLAY INVISIBLE (-3452 5075);
FORCEADD TAP..1
(-3450 5025);
FORCEPROP 3 LASTPIN (-3500 5025) SIG_NAME M_B_CPU1_SA_DQ<18>
J 0
(-3490 5035);
DISPLAY 0.659574 (-3490 5035);
PAINT MONO (-3490 5035);
DISPLAY INVISIBLE (-3490 5035);
FORCEPROP 1 LASTPIN (-3500 5025) BN 18
J 0
(-3512 5033);
DISPLAY 0.489362 (-3512 5033);
PAINT GREEN (-3512 5033);
FORCEPROP 2 LAST CDS_LIB mstr_standard
J 0
(-3450 5025);
DISPLAY 0.723404 (-3450 5025);
PAINT MONO (-3450 5025);
DISPLAY INVISIBLE (-3450 5025);
FORCEPROP 1 LAST BODY_TYPE PLUMBING
J 0
(-3450 5075);
DISPLAY 0.872340 (-3450 5075);
PAINT GREEN (-3450 5075);
DISPLAY INVISIBLE (-3450 5075);
FORCEPROP 1 LAST HDL_TAP TRUE
J 0
(-3125 4900);
DISPLAY 0.872340 (-3125 4900);
DISPLAY INVISIBLE (-3125 4900);
FORCEPROP 1 LAST PATH I180
J 0
(-3452 5025);
DISPLAY 0.872340 (-3452 5025);
PAINT GREEN (-3452 5025);
DISPLAY INVISIBLE (-3452 5025);
FORCEADD TAP..1
(-3450 4925);
FORCEPROP 3 LASTPIN (-3500 4925) SIG_NAME M_B_CPU1_SA_DQ<20>
J 0
(-3490 4935);
DISPLAY 0.659574 (-3490 4935);
PAINT MONO (-3490 4935);
DISPLAY INVISIBLE (-3490 4935);
FORCEPROP 1 LASTPIN (-3500 4925) BN 20
J 0
(-3512 4933);
DISPLAY 0.489362 (-3512 4933);
PAINT GREEN (-3512 4933);
FORCEPROP 2 LAST CDS_LIB mstr_standard
J 0
(-3450 4925);
DISPLAY 0.723404 (-3450 4925);
PAINT MONO (-3450 4925);
DISPLAY INVISIBLE (-3450 4925);
FORCEPROP 1 LAST BODY_TYPE PLUMBING
J 0
(-3450 4975);
DISPLAY 0.872340 (-3450 4975);
PAINT GREEN (-3450 4975);
DISPLAY INVISIBLE (-3450 4975);
FORCEPROP 1 LAST HDL_TAP TRUE
J 0
(-3125 4800);
DISPLAY 0.872340 (-3125 4800);
DISPLAY INVISIBLE (-3125 4800);
FORCEPROP 1 LAST PATH I181
J 0
(-3452 4925);
DISPLAY 0.872340 (-3452 4925);
PAINT GREEN (-3452 4925);
DISPLAY INVISIBLE (-3452 4925);
FORCEADD TAP..1
(-3450 4975);
FORCEPROP 3 LASTPIN (-3500 4975) SIG_NAME M_B_CPU1_SA_DQ<19>
J 0
(-3490 4985);
DISPLAY 0.659574 (-3490 4985);
PAINT MONO (-3490 4985);
DISPLAY INVISIBLE (-3490 4985);
FORCEPROP 1 LASTPIN (-3500 4975) BN 19
J 0
(-3512 4983);
DISPLAY 0.489362 (-3512 4983);
PAINT GREEN (-3512 4983);
FORCEPROP 2 LAST CDS_LIB mstr_standard
J 0
(-3450 4975);
DISPLAY 0.723404 (-3450 4975);
PAINT MONO (-3450 4975);
DISPLAY INVISIBLE (-3450 4975);
FORCEPROP 1 LAST BODY_TYPE PLUMBING
J 0
(-3450 5025);
DISPLAY 0.872340 (-3450 5025);
PAINT GREEN (-3450 5025);
DISPLAY INVISIBLE (-3450 5025);
FORCEPROP 1 LAST HDL_TAP TRUE
J 0
(-3125 4850);
DISPLAY 0.872340 (-3125 4850);
DISPLAY INVISIBLE (-3125 4850);
FORCEPROP 1 LAST PATH I182
J 0
(-3452 4975);
DISPLAY 0.872340 (-3452 4975);
PAINT GREEN (-3452 4975);
DISPLAY INVISIBLE (-3452 4975);
FORCEADD TAP..1
(-3450 4875);
FORCEPROP 3 LASTPIN (-3500 4875) SIG_NAME M_B_CPU1_SA_DQ<21>
J 0
(-3490 4885);
DISPLAY 0.659574 (-3490 4885);
PAINT MONO (-3490 4885);
DISPLAY INVISIBLE (-3490 4885);
FORCEPROP 1 LASTPIN (-3500 4875) BN 21
J 0
(-3512 4883);
DISPLAY 0.489362 (-3512 4883);
PAINT GREEN (-3512 4883);
FORCEPROP 2 LAST CDS_LIB mstr_standard
J 0
(-3450 4875);
DISPLAY 0.723404 (-3450 4875);
PAINT MONO (-3450 4875);
DISPLAY INVISIBLE (-3450 4875);
FORCEPROP 1 LAST BODY_TYPE PLUMBING
J 0
(-3450 4925);
DISPLAY 0.872340 (-3450 4925);
PAINT GREEN (-3450 4925);
DISPLAY INVISIBLE (-3450 4925);
FORCEPROP 1 LAST HDL_TAP TRUE
J 0
(-3125 4750);
DISPLAY 0.872340 (-3125 4750);
DISPLAY INVISIBLE (-3125 4750);
FORCEPROP 1 LAST PATH I183
J 0
(-3452 4875);
DISPLAY 0.872340 (-3452 4875);
PAINT GREEN (-3452 4875);
DISPLAY INVISIBLE (-3452 4875);
FORCEADD TAP..1
(-3450 4825);
FORCEPROP 3 LASTPIN (-3500 4825) SIG_NAME M_B_CPU1_SA_DQ<22>
J 0
(-3490 4835);
DISPLAY 0.659574 (-3490 4835);
PAINT MONO (-3490 4835);
DISPLAY INVISIBLE (-3490 4835);
FORCEPROP 1 LASTPIN (-3500 4825) BN 22
J 0
(-3512 4833);
DISPLAY 0.489362 (-3512 4833);
PAINT GREEN (-3512 4833);
FORCEPROP 2 LAST CDS_LIB mstr_standard
J 0
(-3450 4825);
DISPLAY 0.723404 (-3450 4825);
PAINT MONO (-3450 4825);
DISPLAY INVISIBLE (-3450 4825);
FORCEPROP 1 LAST BODY_TYPE PLUMBING
J 0
(-3450 4875);
DISPLAY 0.872340 (-3450 4875);
PAINT GREEN (-3450 4875);
DISPLAY INVISIBLE (-3450 4875);
FORCEPROP 1 LAST HDL_TAP TRUE
J 0
(-3125 4700);
DISPLAY 0.872340 (-3125 4700);
DISPLAY INVISIBLE (-3125 4700);
FORCEPROP 1 LAST PATH I184
J 0
(-3452 4825);
DISPLAY 0.872340 (-3452 4825);
PAINT GREEN (-3452 4825);
DISPLAY INVISIBLE (-3452 4825);
FORCEADD TAP..1
(-3450 4775);
FORCEPROP 3 LASTPIN (-3500 4775) SIG_NAME M_B_CPU1_SA_DQ<23>
J 0
(-3490 4785);
DISPLAY 0.659574 (-3490 4785);
PAINT MONO (-3490 4785);
DISPLAY INVISIBLE (-3490 4785);
FORCEPROP 1 LASTPIN (-3500 4775) BN 23
J 0
(-3512 4783);
DISPLAY 0.489362 (-3512 4783);
PAINT GREEN (-3512 4783);
FORCEPROP 2 LAST CDS_LIB mstr_standard
J 0
(-3450 4775);
DISPLAY 0.723404 (-3450 4775);
PAINT MONO (-3450 4775);
DISPLAY INVISIBLE (-3450 4775);
FORCEPROP 1 LAST BODY_TYPE PLUMBING
J 0
(-3450 4825);
DISPLAY 0.872340 (-3450 4825);
PAINT GREEN (-3450 4825);
DISPLAY INVISIBLE (-3450 4825);
FORCEPROP 1 LAST HDL_TAP TRUE
J 0
(-3125 4650);
DISPLAY 0.872340 (-3125 4650);
DISPLAY INVISIBLE (-3125 4650);
FORCEPROP 1 LAST PATH I185
J 0
(-3452 4775);
DISPLAY 0.872340 (-3452 4775);
PAINT GREEN (-3452 4775);
DISPLAY INVISIBLE (-3452 4775);
FORCEADD TAP..1
(-3450 4675);
FORCEPROP 3 LASTPIN (-3500 4675) SIG_NAME M_B_CPU1_SA_DQ<24>
J 0
(-3490 4685);
DISPLAY 0.659574 (-3490 4685);
PAINT MONO (-3490 4685);
DISPLAY INVISIBLE (-3490 4685);
FORCEPROP 1 LASTPIN (-3500 4675) BN 24
J 0
(-3512 4683);
DISPLAY 0.489362 (-3512 4683);
PAINT GREEN (-3512 4683);
FORCEPROP 2 LAST CDS_LIB mstr_standard
J 0
(-3450 4675);
DISPLAY 0.723404 (-3450 4675);
PAINT MONO (-3450 4675);
DISPLAY INVISIBLE (-3450 4675);
FORCEPROP 1 LAST BODY_TYPE PLUMBING
J 0
(-3450 4725);
DISPLAY 0.872340 (-3450 4725);
PAINT GREEN (-3450 4725);
DISPLAY INVISIBLE (-3450 4725);
FORCEPROP 1 LAST HDL_TAP TRUE
J 0
(-3125 4550);
DISPLAY 0.872340 (-3125 4550);
DISPLAY INVISIBLE (-3125 4550);
FORCEPROP 1 LAST PATH I186
J 0
(-3452 4675);
DISPLAY 0.872340 (-3452 4675);
PAINT GREEN (-3452 4675);
DISPLAY INVISIBLE (-3452 4675);
FORCEADD TAP..1
(-3450 4625);
FORCEPROP 3 LASTPIN (-3500 4625) SIG_NAME M_B_CPU1_SA_DQ<25>
J 0
(-3490 4635);
DISPLAY 0.659574 (-3490 4635);
PAINT MONO (-3490 4635);
DISPLAY INVISIBLE (-3490 4635);
FORCEPROP 1 LASTPIN (-3500 4625) BN 25
J 0
(-3512 4633);
DISPLAY 0.489362 (-3512 4633);
PAINT GREEN (-3512 4633);
FORCEPROP 2 LAST CDS_LIB mstr_standard
J 0
(-3450 4625);
DISPLAY 0.723404 (-3450 4625);
PAINT MONO (-3450 4625);
DISPLAY INVISIBLE (-3450 4625);
FORCEPROP 1 LAST BODY_TYPE PLUMBING
J 0
(-3450 4675);
DISPLAY 0.872340 (-3450 4675);
PAINT GREEN (-3450 4675);
DISPLAY INVISIBLE (-3450 4675);
FORCEPROP 1 LAST HDL_TAP TRUE
J 0
(-3125 4500);
DISPLAY 0.872340 (-3125 4500);
DISPLAY INVISIBLE (-3125 4500);
FORCEPROP 1 LAST PATH I187
J 0
(-3452 4625);
DISPLAY 0.872340 (-3452 4625);
PAINT GREEN (-3452 4625);
DISPLAY INVISIBLE (-3452 4625);
FORCEADD TAP..1
(-3450 4575);
FORCEPROP 3 LASTPIN (-3500 4575) SIG_NAME M_B_CPU1_SA_DQ<26>
J 0
(-3490 4585);
DISPLAY 0.659574 (-3490 4585);
PAINT MONO (-3490 4585);
DISPLAY INVISIBLE (-3490 4585);
FORCEPROP 1 LASTPIN (-3500 4575) BN 26
J 0
(-3512 4583);
DISPLAY 0.489362 (-3512 4583);
PAINT GREEN (-3512 4583);
FORCEPROP 2 LAST CDS_LIB mstr_standard
J 0
(-3450 4575);
DISPLAY 0.723404 (-3450 4575);
PAINT MONO (-3450 4575);
DISPLAY INVISIBLE (-3450 4575);
FORCEPROP 1 LAST BODY_TYPE PLUMBING
J 0
(-3450 4625);
DISPLAY 0.872340 (-3450 4625);
PAINT GREEN (-3450 4625);
DISPLAY INVISIBLE (-3450 4625);
FORCEPROP 1 LAST HDL_TAP TRUE
J 0
(-3125 4450);
DISPLAY 0.872340 (-3125 4450);
DISPLAY INVISIBLE (-3125 4450);
FORCEPROP 1 LAST PATH I188
J 0
(-3452 4575);
DISPLAY 0.872340 (-3452 4575);
PAINT GREEN (-3452 4575);
DISPLAY INVISIBLE (-3452 4575);
FORCEADD TAP..1
(-3450 4525);
FORCEPROP 3 LASTPIN (-3500 4525) SIG_NAME M_B_CPU1_SA_DQ<27>
J 0
(-3490 4535);
DISPLAY 0.659574 (-3490 4535);
PAINT MONO (-3490 4535);
DISPLAY INVISIBLE (-3490 4535);
FORCEPROP 1 LASTPIN (-3500 4525) BN 27
J 0
(-3512 4533);
DISPLAY 0.489362 (-3512 4533);
PAINT GREEN (-3512 4533);
FORCEPROP 2 LAST CDS_LIB mstr_standard
J 0
(-3450 4525);
DISPLAY 0.723404 (-3450 4525);
PAINT MONO (-3450 4525);
DISPLAY INVISIBLE (-3450 4525);
FORCEPROP 1 LAST BODY_TYPE PLUMBING
J 0
(-3450 4575);
DISPLAY 0.872340 (-3450 4575);
PAINT GREEN (-3450 4575);
DISPLAY INVISIBLE (-3450 4575);
FORCEPROP 1 LAST HDL_TAP TRUE
J 0
(-3125 4400);
DISPLAY 0.872340 (-3125 4400);
DISPLAY INVISIBLE (-3125 4400);
FORCEPROP 1 LAST PATH I189
J 0
(-3452 4525);
DISPLAY 0.872340 (-3452 4525);
PAINT GREEN (-3452 4525);
DISPLAY INVISIBLE (-3452 4525);
FORCEADD TAP..1
(-3450 4425);
FORCEPROP 3 LASTPIN (-3500 4425) SIG_NAME M_B_CPU1_SA_DQ<29>
J 0
(-3490 4435);
DISPLAY 0.659574 (-3490 4435);
PAINT MONO (-3490 4435);
DISPLAY INVISIBLE (-3490 4435);
FORCEPROP 1 LASTPIN (-3500 4425) BN 29
J 0
(-3512 4433);
DISPLAY 0.489362 (-3512 4433);
PAINT GREEN (-3512 4433);
FORCEPROP 2 LAST CDS_LIB mstr_standard
J 0
(-3450 4425);
DISPLAY 0.723404 (-3450 4425);
PAINT MONO (-3450 4425);
DISPLAY INVISIBLE (-3450 4425);
FORCEPROP 1 LAST BODY_TYPE PLUMBING
J 0
(-3450 4475);
DISPLAY 0.872340 (-3450 4475);
PAINT GREEN (-3450 4475);
DISPLAY INVISIBLE (-3450 4475);
FORCEPROP 1 LAST HDL_TAP TRUE
J 0
(-3125 4300);
DISPLAY 0.872340 (-3125 4300);
DISPLAY INVISIBLE (-3125 4300);
FORCEPROP 1 LAST PATH I190
J 0
(-3452 4425);
DISPLAY 0.872340 (-3452 4425);
PAINT GREEN (-3452 4425);
DISPLAY INVISIBLE (-3452 4425);
FORCEADD TAP..1
(-3450 4375);
FORCEPROP 3 LASTPIN (-3500 4375) SIG_NAME M_B_CPU1_SA_DQ<30>
J 0
(-3490 4385);
DISPLAY 0.659574 (-3490 4385);
PAINT MONO (-3490 4385);
DISPLAY INVISIBLE (-3490 4385);
FORCEPROP 1 LASTPIN (-3500 4375) BN 30
J 0
(-3512 4383);
DISPLAY 0.489362 (-3512 4383);
PAINT GREEN (-3512 4383);
FORCEPROP 2 LAST CDS_LIB mstr_standard
J 0
(-3450 4375);
DISPLAY 0.723404 (-3450 4375);
PAINT MONO (-3450 4375);
DISPLAY INVISIBLE (-3450 4375);
FORCEPROP 1 LAST BODY_TYPE PLUMBING
J 0
(-3450 4425);
DISPLAY 0.872340 (-3450 4425);
PAINT GREEN (-3450 4425);
DISPLAY INVISIBLE (-3450 4425);
FORCEPROP 1 LAST HDL_TAP TRUE
J 0
(-3125 4250);
DISPLAY 0.872340 (-3125 4250);
DISPLAY INVISIBLE (-3125 4250);
FORCEPROP 1 LAST PATH I191
J 0
(-3452 4375);
DISPLAY 0.872340 (-3452 4375);
PAINT GREEN (-3452 4375);
DISPLAY INVISIBLE (-3452 4375);
FORCEADD TAP..1
(-3450 4475);
FORCEPROP 3 LASTPIN (-3500 4475) SIG_NAME M_B_CPU1_SA_DQ<28>
J 0
(-3490 4485);
DISPLAY 0.659574 (-3490 4485);
PAINT MONO (-3490 4485);
DISPLAY INVISIBLE (-3490 4485);
FORCEPROP 1 LASTPIN (-3500 4475) BN 28
J 0
(-3512 4483);
DISPLAY 0.489362 (-3512 4483);
PAINT GREEN (-3512 4483);
FORCEPROP 2 LAST CDS_LIB mstr_standard
J 0
(-3450 4475);
DISPLAY 0.723404 (-3450 4475);
PAINT MONO (-3450 4475);
DISPLAY INVISIBLE (-3450 4475);
FORCEPROP 1 LAST BODY_TYPE PLUMBING
J 0
(-3450 4525);
DISPLAY 0.872340 (-3450 4525);
PAINT GREEN (-3450 4525);
DISPLAY INVISIBLE (-3450 4525);
FORCEPROP 1 LAST HDL_TAP TRUE
J 0
(-3125 4350);
DISPLAY 0.872340 (-3125 4350);
DISPLAY INVISIBLE (-3125 4350);
FORCEPROP 1 LAST PATH I192
J 0
(-3452 4475);
DISPLAY 0.872340 (-3452 4475);
PAINT GREEN (-3452 4475);
DISPLAY INVISIBLE (-3452 4475);
FORCEADD TAP..1
(-3450 4325);
FORCEPROP 3 LASTPIN (-3500 4325) SIG_NAME M_B_CPU1_SA_DQ<31>
J 0
(-3490 4335);
DISPLAY 0.659574 (-3490 4335);
PAINT MONO (-3490 4335);
DISPLAY INVISIBLE (-3490 4335);
FORCEPROP 1 LASTPIN (-3500 4325) BN 31
J 0
(-3512 4333);
DISPLAY 0.489362 (-3512 4333);
PAINT GREEN (-3512 4333);
FORCEPROP 2 LAST CDS_LIB mstr_standard
J 0
(-3450 4325);
DISPLAY 0.723404 (-3450 4325);
PAINT MONO (-3450 4325);
DISPLAY INVISIBLE (-3450 4325);
FORCEPROP 1 LAST BODY_TYPE PLUMBING
J 0
(-3450 4375);
DISPLAY 0.872340 (-3450 4375);
PAINT GREEN (-3450 4375);
DISPLAY INVISIBLE (-3450 4375);
FORCEPROP 1 LAST HDL_TAP TRUE
J 0
(-3125 4200);
DISPLAY 0.872340 (-3125 4200);
DISPLAY INVISIBLE (-3125 4200);
FORCEPROP 1 LAST PATH I193
J 0
(-3452 4325);
DISPLAY 0.872340 (-3452 4325);
PAINT GREEN (-3452 4325);
DISPLAY INVISIBLE (-3452 4325);
FORCEADD TAP..1
(-3450 4125);
FORCEPROP 3 LASTPIN (-3500 4125) SIG_NAME M_B_CPU1_SB_DQ<2>
J 0
(-3490 4135);
DISPLAY 0.659574 (-3490 4135);
PAINT MONO (-3490 4135);
DISPLAY INVISIBLE (-3490 4135);
FORCEPROP 1 LASTPIN (-3500 4125) BN 2
J 0
(-3512 4133);
DISPLAY 0.489362 (-3512 4133);
PAINT GREEN (-3512 4133);
FORCEPROP 2 LAST CDS_LIB mstr_standard
J 0
(-3450 4125);
DISPLAY 0.723404 (-3450 4125);
PAINT MONO (-3450 4125);
DISPLAY INVISIBLE (-3450 4125);
FORCEPROP 1 LAST BODY_TYPE PLUMBING
J 0
(-3450 4175);
DISPLAY 0.872340 (-3450 4175);
PAINT GREEN (-3450 4175);
DISPLAY INVISIBLE (-3450 4175);
FORCEPROP 1 LAST HDL_TAP TRUE
J 0
(-3125 4000);
DISPLAY 0.872340 (-3125 4000);
DISPLAY INVISIBLE (-3125 4000);
FORCEPROP 1 LAST PATH I194
J 0
(-3452 4125);
DISPLAY 0.872340 (-3452 4125);
PAINT GREEN (-3452 4125);
DISPLAY INVISIBLE (-3452 4125);
FORCEADD TAP..1
(-3450 4175);
FORCEPROP 3 LASTPIN (-3500 4175) SIG_NAME M_B_CPU1_SB_DQ<1>
J 0
(-3490 4185);
DISPLAY 0.659574 (-3490 4185);
PAINT MONO (-3490 4185);
DISPLAY INVISIBLE (-3490 4185);
FORCEPROP 1 LASTPIN (-3500 4175) BN 1
J 0
(-3512 4183);
DISPLAY 0.489362 (-3512 4183);
PAINT GREEN (-3512 4183);
FORCEPROP 2 LAST CDS_LIB mstr_standard
J 0
(-3450 4175);
DISPLAY 0.723404 (-3450 4175);
PAINT MONO (-3450 4175);
DISPLAY INVISIBLE (-3450 4175);
FORCEPROP 1 LAST BODY_TYPE PLUMBING
J 0
(-3450 4225);
DISPLAY 0.872340 (-3450 4225);
PAINT GREEN (-3450 4225);
DISPLAY INVISIBLE (-3450 4225);
FORCEPROP 1 LAST HDL_TAP TRUE
J 0
(-3125 4050);
DISPLAY 0.872340 (-3125 4050);
DISPLAY INVISIBLE (-3125 4050);
FORCEPROP 1 LAST PATH I195
J 0
(-3452 4175);
DISPLAY 0.872340 (-3452 4175);
PAINT GREEN (-3452 4175);
DISPLAY INVISIBLE (-3452 4175);
FORCEADD TAP..1
(-3450 4225);
FORCEPROP 3 LASTPIN (-3500 4225) SIG_NAME M_B_CPU1_SB_DQ<0>
J 0
(-3490 4235);
DISPLAY 0.659574 (-3490 4235);
PAINT MONO (-3490 4235);
DISPLAY INVISIBLE (-3490 4235);
FORCEPROP 1 LASTPIN (-3500 4225) BN 0
J 0
(-3512 4233);
DISPLAY 0.489362 (-3512 4233);
PAINT GREEN (-3512 4233);
FORCEPROP 2 LAST CDS_LIB mstr_standard
J 0
(-3450 4225);
DISPLAY 0.723404 (-3450 4225);
PAINT MONO (-3450 4225);
DISPLAY INVISIBLE (-3450 4225);
FORCEPROP 1 LAST BODY_TYPE PLUMBING
J 0
(-3450 4275);
DISPLAY 0.872340 (-3450 4275);
PAINT GREEN (-3450 4275);
DISPLAY INVISIBLE (-3450 4275);
FORCEPROP 1 LAST HDL_TAP TRUE
J 0
(-3125 4100);
DISPLAY 0.872340 (-3125 4100);
DISPLAY INVISIBLE (-3125 4100);
FORCEPROP 1 LAST PATH I196
J 0
(-3452 4225);
DISPLAY 0.872340 (-3452 4225);
PAINT GREEN (-3452 4225);
DISPLAY INVISIBLE (-3452 4225);
FORCEADD OFFPAGE..6
R 2
(-2850 2475);
FORCEPROP 2 LAST $XR0 98 
J 0
(-2636 2475);
DISPLAY 0.638298 (-2636 2475);
PAINT MONO (-2636 2475);
FORCEPROP 2 LAST PATH I197
J 0
(-2625 2525);
DISPLAY 1.021277 (-2625 2525);
DISPLAY INVISIBLE (-2625 2525);
FORCEPROP 1 LAST COMMENT_BODY TRUE
J 2
(-2950 2400);
DISPLAY 0.872340 (-2950 2400);
PAINT GREEN (-2950 2400);
DISPLAY INVISIBLE (-2950 2400);
FORCEPROP 1 LAST OFFPAGE TRUE
J 2
(-3175 2350);
DISPLAY 0.872340 (-3175 2350);
PAINT GREEN (-3175 2350);
DISPLAY INVISIBLE (-3175 2350);
FORCEPROP 2 LAST CDS_LIB mstr_standard
J 2
(-2850 2475);
DISPLAY 0.723404 (-2850 2475);
PAINT MONO (-2850 2475);
DISPLAY INVISIBLE (-2850 2475);
FORCEADD TAP..1
(-3450 4075);
FORCEPROP 3 LASTPIN (-3500 4075) SIG_NAME M_B_CPU1_SB_DQ<3>
J 0
(-3490 4085);
DISPLAY 0.659574 (-3490 4085);
PAINT MONO (-3490 4085);
DISPLAY INVISIBLE (-3490 4085);
FORCEPROP 1 LASTPIN (-3500 4075) BN 3
J 0
(-3512 4083);
DISPLAY 0.489362 (-3512 4083);
PAINT GREEN (-3512 4083);
FORCEPROP 2 LAST CDS_LIB mstr_standard
J 0
(-3450 4075);
DISPLAY 0.723404 (-3450 4075);
PAINT MONO (-3450 4075);
DISPLAY INVISIBLE (-3450 4075);
FORCEPROP 1 LAST BODY_TYPE PLUMBING
J 0
(-3450 4125);
DISPLAY 0.872340 (-3450 4125);
PAINT GREEN (-3450 4125);
DISPLAY INVISIBLE (-3450 4125);
FORCEPROP 1 LAST HDL_TAP TRUE
J 0
(-3125 3950);
DISPLAY 0.872340 (-3125 3950);
DISPLAY INVISIBLE (-3125 3950);
FORCEPROP 1 LAST PATH I198
J 0
(-3452 4075);
DISPLAY 0.872340 (-3452 4075);
PAINT GREEN (-3452 4075);
DISPLAY INVISIBLE (-3452 4075);
FORCEADD TAP..1
(-3450 4025);
FORCEPROP 3 LASTPIN (-3500 4025) SIG_NAME M_B_CPU1_SB_DQ<4>
J 0
(-3490 4035);
DISPLAY 0.659574 (-3490 4035);
PAINT MONO (-3490 4035);
DISPLAY INVISIBLE (-3490 4035);
FORCEPROP 1 LASTPIN (-3500 4025) BN 4
J 0
(-3512 4033);
DISPLAY 0.489362 (-3512 4033);
PAINT GREEN (-3512 4033);
FORCEPROP 2 LAST CDS_LIB mstr_standard
J 0
(-3450 4025);
DISPLAY 0.723404 (-3450 4025);
PAINT MONO (-3450 4025);
DISPLAY INVISIBLE (-3450 4025);
FORCEPROP 1 LAST BODY_TYPE PLUMBING
J 0
(-3450 4075);
DISPLAY 0.872340 (-3450 4075);
PAINT GREEN (-3450 4075);
DISPLAY INVISIBLE (-3450 4075);
FORCEPROP 1 LAST HDL_TAP TRUE
J 0
(-3125 3900);
DISPLAY 0.872340 (-3125 3900);
DISPLAY INVISIBLE (-3125 3900);
FORCEPROP 1 LAST PATH I199
J 0
(-3452 4025);
DISPLAY 0.872340 (-3452 4025);
PAINT GREEN (-3452 4025);
DISPLAY INVISIBLE (-3452 4025);
FORCEADD TAP..1
(-3450 3975);
FORCEPROP 3 LASTPIN (-3500 3975) SIG_NAME M_B_CPU1_SB_DQ<5>
J 0
(-3490 3985);
DISPLAY 0.659574 (-3490 3985);
PAINT MONO (-3490 3985);
DISPLAY INVISIBLE (-3490 3985);
FORCEPROP 1 LASTPIN (-3500 3975) BN 5
J 0
(-3512 3983);
DISPLAY 0.489362 (-3512 3983);
PAINT GREEN (-3512 3983);
FORCEPROP 2 LAST CDS_LIB mstr_standard
J 0
(-3450 3975);
DISPLAY 0.723404 (-3450 3975);
PAINT MONO (-3450 3975);
DISPLAY INVISIBLE (-3450 3975);
FORCEPROP 1 LAST BODY_TYPE PLUMBING
J 0
(-3450 4025);
DISPLAY 0.872340 (-3450 4025);
PAINT GREEN (-3450 4025);
DISPLAY INVISIBLE (-3450 4025);
FORCEPROP 1 LAST HDL_TAP TRUE
J 0
(-3125 3850);
DISPLAY 0.872340 (-3125 3850);
DISPLAY INVISIBLE (-3125 3850);
FORCEPROP 1 LAST PATH I200
J 0
(-3452 3975);
DISPLAY 0.872340 (-3452 3975);
PAINT GREEN (-3452 3975);
DISPLAY INVISIBLE (-3452 3975);
FORCEADD TAP..1
(-3450 3875);
FORCEPROP 3 LASTPIN (-3500 3875) SIG_NAME M_B_CPU1_SB_DQ<7>
J 0
(-3490 3885);
DISPLAY 0.659574 (-3490 3885);
PAINT MONO (-3490 3885);
DISPLAY INVISIBLE (-3490 3885);
FORCEPROP 1 LASTPIN (-3500 3875) BN 7
J 0
(-3512 3883);
DISPLAY 0.489362 (-3512 3883);
PAINT GREEN (-3512 3883);
FORCEPROP 2 LAST CDS_LIB mstr_standard
J 0
(-3450 3875);
DISPLAY 0.723404 (-3450 3875);
PAINT MONO (-3450 3875);
DISPLAY INVISIBLE (-3450 3875);
FORCEPROP 1 LAST BODY_TYPE PLUMBING
J 0
(-3450 3925);
DISPLAY 0.872340 (-3450 3925);
PAINT GREEN (-3450 3925);
DISPLAY INVISIBLE (-3450 3925);
FORCEPROP 1 LAST HDL_TAP TRUE
J 0
(-3125 3750);
DISPLAY 0.872340 (-3125 3750);
DISPLAY INVISIBLE (-3125 3750);
FORCEPROP 1 LAST PATH I201
J 0
(-3452 3875);
DISPLAY 0.872340 (-3452 3875);
PAINT GREEN (-3452 3875);
DISPLAY INVISIBLE (-3452 3875);
FORCEADD TAP..1
(-3450 3925);
FORCEPROP 3 LASTPIN (-3500 3925) SIG_NAME M_B_CPU1_SB_DQ<6>
J 0
(-3490 3935);
DISPLAY 0.659574 (-3490 3935);
PAINT MONO (-3490 3935);
DISPLAY INVISIBLE (-3490 3935);
FORCEPROP 1 LASTPIN (-3500 3925) BN 6
J 0
(-3512 3933);
DISPLAY 0.489362 (-3512 3933);
PAINT GREEN (-3512 3933);
FORCEPROP 2 LAST CDS_LIB mstr_standard
J 0
(-3450 3925);
DISPLAY 0.723404 (-3450 3925);
PAINT MONO (-3450 3925);
DISPLAY INVISIBLE (-3450 3925);
FORCEPROP 1 LAST BODY_TYPE PLUMBING
J 0
(-3450 3975);
DISPLAY 0.872340 (-3450 3975);
PAINT GREEN (-3450 3975);
DISPLAY INVISIBLE (-3450 3975);
FORCEPROP 1 LAST HDL_TAP TRUE
J 0
(-3125 3800);
DISPLAY 0.872340 (-3125 3800);
DISPLAY INVISIBLE (-3125 3800);
FORCEPROP 1 LAST PATH I202
J 0
(-3452 3925);
DISPLAY 0.872340 (-3452 3925);
PAINT GREEN (-3452 3925);
DISPLAY INVISIBLE (-3452 3925);
FORCEADD TAP..1
(-3450 3775);
FORCEPROP 3 LASTPIN (-3500 3775) SIG_NAME M_B_CPU1_SB_DQ<8>
J 0
(-3490 3785);
DISPLAY 0.659574 (-3490 3785);
PAINT MONO (-3490 3785);
DISPLAY INVISIBLE (-3490 3785);
FORCEPROP 1 LASTPIN (-3500 3775) BN 8
J 0
(-3512 3783);
DISPLAY 0.489362 (-3512 3783);
PAINT GREEN (-3512 3783);
FORCEPROP 2 LAST CDS_LIB mstr_standard
J 0
(-3450 3775);
DISPLAY 0.723404 (-3450 3775);
PAINT MONO (-3450 3775);
DISPLAY INVISIBLE (-3450 3775);
FORCEPROP 1 LAST BODY_TYPE PLUMBING
J 0
(-3450 3825);
DISPLAY 0.872340 (-3450 3825);
PAINT GREEN (-3450 3825);
DISPLAY INVISIBLE (-3450 3825);
FORCEPROP 1 LAST HDL_TAP TRUE
J 0
(-3125 3650);
DISPLAY 0.872340 (-3125 3650);
DISPLAY INVISIBLE (-3125 3650);
FORCEPROP 1 LAST PATH I203
J 0
(-3452 3775);
DISPLAY 0.872340 (-3452 3775);
PAINT GREEN (-3452 3775);
DISPLAY INVISIBLE (-3452 3775);
FORCEADD TAP..1
(-3450 3625);
FORCEPROP 3 LASTPIN (-3500 3625) SIG_NAME M_B_CPU1_SB_DQ<11>
J 0
(-3490 3635);
DISPLAY 0.659574 (-3490 3635);
PAINT MONO (-3490 3635);
DISPLAY INVISIBLE (-3490 3635);
FORCEPROP 1 LASTPIN (-3500 3625) BN 11
J 0
(-3512 3633);
DISPLAY 0.489362 (-3512 3633);
PAINT GREEN (-3512 3633);
FORCEPROP 2 LAST CDS_LIB mstr_standard
J 0
(-3450 3625);
DISPLAY 0.723404 (-3450 3625);
PAINT MONO (-3450 3625);
DISPLAY INVISIBLE (-3450 3625);
FORCEPROP 1 LAST BODY_TYPE PLUMBING
J 0
(-3450 3675);
DISPLAY 0.872340 (-3450 3675);
PAINT GREEN (-3450 3675);
DISPLAY INVISIBLE (-3450 3675);
FORCEPROP 1 LAST HDL_TAP TRUE
J 0
(-3125 3500);
DISPLAY 0.872340 (-3125 3500);
DISPLAY INVISIBLE (-3125 3500);
FORCEPROP 1 LAST PATH I204
J 0
(-3452 3625);
DISPLAY 0.872340 (-3452 3625);
PAINT GREEN (-3452 3625);
DISPLAY INVISIBLE (-3452 3625);
FORCEADD TAP..1
(-3450 3725);
FORCEPROP 3 LASTPIN (-3500 3725) SIG_NAME M_B_CPU1_SB_DQ<9>
J 0
(-3490 3735);
DISPLAY 0.659574 (-3490 3735);
PAINT MONO (-3490 3735);
DISPLAY INVISIBLE (-3490 3735);
FORCEPROP 1 LASTPIN (-3500 3725) BN 9
J 0
(-3512 3733);
DISPLAY 0.489362 (-3512 3733);
PAINT GREEN (-3512 3733);
FORCEPROP 2 LAST CDS_LIB mstr_standard
J 0
(-3450 3725);
DISPLAY 0.723404 (-3450 3725);
PAINT MONO (-3450 3725);
DISPLAY INVISIBLE (-3450 3725);
FORCEPROP 1 LAST BODY_TYPE PLUMBING
J 0
(-3450 3775);
DISPLAY 0.872340 (-3450 3775);
PAINT GREEN (-3450 3775);
DISPLAY INVISIBLE (-3450 3775);
FORCEPROP 1 LAST HDL_TAP TRUE
J 0
(-3125 3600);
DISPLAY 0.872340 (-3125 3600);
DISPLAY INVISIBLE (-3125 3600);
FORCEPROP 1 LAST PATH I205
J 0
(-3452 3725);
DISPLAY 0.872340 (-3452 3725);
PAINT GREEN (-3452 3725);
DISPLAY INVISIBLE (-3452 3725);
FORCEADD TAP..1
(-3450 3675);
FORCEPROP 3 LASTPIN (-3500 3675) SIG_NAME M_B_CPU1_SB_DQ<10>
J 0
(-3490 3685);
DISPLAY 0.659574 (-3490 3685);
PAINT MONO (-3490 3685);
DISPLAY INVISIBLE (-3490 3685);
FORCEPROP 1 LASTPIN (-3500 3675) BN 10
J 0
(-3512 3683);
DISPLAY 0.489362 (-3512 3683);
PAINT GREEN (-3512 3683);
FORCEPROP 2 LAST CDS_LIB mstr_standard
J 0
(-3450 3675);
DISPLAY 0.723404 (-3450 3675);
PAINT MONO (-3450 3675);
DISPLAY INVISIBLE (-3450 3675);
FORCEPROP 1 LAST BODY_TYPE PLUMBING
J 0
(-3450 3725);
DISPLAY 0.872340 (-3450 3725);
PAINT GREEN (-3450 3725);
DISPLAY INVISIBLE (-3450 3725);
FORCEPROP 1 LAST HDL_TAP TRUE
J 0
(-3125 3550);
DISPLAY 0.872340 (-3125 3550);
DISPLAY INVISIBLE (-3125 3550);
FORCEPROP 1 LAST PATH I206
J 0
(-3452 3675);
DISPLAY 0.872340 (-3452 3675);
PAINT GREEN (-3452 3675);
DISPLAY INVISIBLE (-3452 3675);
FORCEADD TAP..1
(-3450 3575);
FORCEPROP 3 LASTPIN (-3500 3575) SIG_NAME M_B_CPU1_SB_DQ<12>
J 0
(-3490 3585);
DISPLAY 0.659574 (-3490 3585);
PAINT MONO (-3490 3585);
DISPLAY INVISIBLE (-3490 3585);
FORCEPROP 1 LASTPIN (-3500 3575) BN 12
J 0
(-3512 3583);
DISPLAY 0.489362 (-3512 3583);
PAINT GREEN (-3512 3583);
FORCEPROP 2 LAST CDS_LIB mstr_standard
J 0
(-3450 3575);
DISPLAY 0.723404 (-3450 3575);
PAINT MONO (-3450 3575);
DISPLAY INVISIBLE (-3450 3575);
FORCEPROP 1 LAST BODY_TYPE PLUMBING
J 0
(-3450 3625);
DISPLAY 0.872340 (-3450 3625);
PAINT GREEN (-3450 3625);
DISPLAY INVISIBLE (-3450 3625);
FORCEPROP 1 LAST HDL_TAP TRUE
J 0
(-3125 3450);
DISPLAY 0.872340 (-3125 3450);
DISPLAY INVISIBLE (-3125 3450);
FORCEPROP 1 LAST PATH I207
J 0
(-3452 3575);
DISPLAY 0.872340 (-3452 3575);
PAINT GREEN (-3452 3575);
DISPLAY INVISIBLE (-3452 3575);
FORCEADD TAP..1
(-3450 3525);
FORCEPROP 3 LASTPIN (-3500 3525) SIG_NAME M_B_CPU1_SB_DQ<13>
J 0
(-3490 3535);
DISPLAY 0.659574 (-3490 3535);
PAINT MONO (-3490 3535);
DISPLAY INVISIBLE (-3490 3535);
FORCEPROP 1 LASTPIN (-3500 3525) BN 13
J 0
(-3512 3533);
DISPLAY 0.489362 (-3512 3533);
PAINT GREEN (-3512 3533);
FORCEPROP 2 LAST CDS_LIB mstr_standard
J 0
(-3450 3525);
DISPLAY 0.723404 (-3450 3525);
PAINT MONO (-3450 3525);
DISPLAY INVISIBLE (-3450 3525);
FORCEPROP 1 LAST BODY_TYPE PLUMBING
J 0
(-3450 3575);
DISPLAY 0.872340 (-3450 3575);
PAINT GREEN (-3450 3575);
DISPLAY INVISIBLE (-3450 3575);
FORCEPROP 1 LAST HDL_TAP TRUE
J 0
(-3125 3400);
DISPLAY 0.872340 (-3125 3400);
DISPLAY INVISIBLE (-3125 3400);
FORCEPROP 1 LAST PATH I208
J 0
(-3452 3525);
DISPLAY 0.872340 (-3452 3525);
PAINT GREEN (-3452 3525);
DISPLAY INVISIBLE (-3452 3525);
FORCEADD TAP..1
(-3450 3425);
FORCEPROP 3 LASTPIN (-3500 3425) SIG_NAME M_B_CPU1_SB_DQ<15>
J 0
(-3490 3435);
DISPLAY 0.659574 (-3490 3435);
PAINT MONO (-3490 3435);
DISPLAY INVISIBLE (-3490 3435);
FORCEPROP 1 LASTPIN (-3500 3425) BN 15
J 0
(-3512 3433);
DISPLAY 0.489362 (-3512 3433);
PAINT GREEN (-3512 3433);
FORCEPROP 2 LAST CDS_LIB mstr_standard
J 0
(-3450 3425);
DISPLAY 0.723404 (-3450 3425);
PAINT MONO (-3450 3425);
DISPLAY INVISIBLE (-3450 3425);
FORCEPROP 1 LAST BODY_TYPE PLUMBING
J 0
(-3450 3475);
DISPLAY 0.872340 (-3450 3475);
PAINT GREEN (-3450 3475);
DISPLAY INVISIBLE (-3450 3475);
FORCEPROP 1 LAST HDL_TAP TRUE
J 0
(-3125 3300);
DISPLAY 0.872340 (-3125 3300);
DISPLAY INVISIBLE (-3125 3300);
FORCEPROP 1 LAST PATH I209
J 0
(-3452 3425);
DISPLAY 0.872340 (-3452 3425);
PAINT GREEN (-3452 3425);
DISPLAY INVISIBLE (-3452 3425);
FORCEADD TAP..1
(-3450 3475);
FORCEPROP 3 LASTPIN (-3500 3475) SIG_NAME M_B_CPU1_SB_DQ<14>
J 0
(-3490 3485);
DISPLAY 0.659574 (-3490 3485);
PAINT MONO (-3490 3485);
DISPLAY INVISIBLE (-3490 3485);
FORCEPROP 1 LASTPIN (-3500 3475) BN 14
J 0
(-3512 3483);
DISPLAY 0.489362 (-3512 3483);
PAINT GREEN (-3512 3483);
FORCEPROP 2 LAST CDS_LIB mstr_standard
J 0
(-3450 3475);
DISPLAY 0.723404 (-3450 3475);
PAINT MONO (-3450 3475);
DISPLAY INVISIBLE (-3450 3475);
FORCEPROP 1 LAST BODY_TYPE PLUMBING
J 0
(-3450 3525);
DISPLAY 0.872340 (-3450 3525);
PAINT GREEN (-3450 3525);
DISPLAY INVISIBLE (-3450 3525);
FORCEPROP 1 LAST HDL_TAP TRUE
J 0
(-3125 3350);
DISPLAY 0.872340 (-3125 3350);
DISPLAY INVISIBLE (-3125 3350);
FORCEPROP 1 LAST PATH I210
J 0
(-3452 3475);
DISPLAY 0.872340 (-3452 3475);
PAINT GREEN (-3452 3475);
DISPLAY INVISIBLE (-3452 3475);
FORCEADD TAP..1
(-3450 3325);
FORCEPROP 3 LASTPIN (-3500 3325) SIG_NAME M_B_CPU1_SB_DQ<16>
J 0
(-3490 3335);
DISPLAY 0.659574 (-3490 3335);
PAINT MONO (-3490 3335);
DISPLAY INVISIBLE (-3490 3335);
FORCEPROP 1 LASTPIN (-3500 3325) BN 16
J 0
(-3512 3333);
DISPLAY 0.489362 (-3512 3333);
PAINT GREEN (-3512 3333);
FORCEPROP 2 LAST CDS_LIB mstr_standard
J 0
(-3450 3325);
DISPLAY 0.723404 (-3450 3325);
PAINT MONO (-3450 3325);
DISPLAY INVISIBLE (-3450 3325);
FORCEPROP 1 LAST BODY_TYPE PLUMBING
J 0
(-3450 3375);
DISPLAY 0.872340 (-3450 3375);
PAINT GREEN (-3450 3375);
DISPLAY INVISIBLE (-3450 3375);
FORCEPROP 1 LAST HDL_TAP TRUE
J 0
(-3125 3200);
DISPLAY 0.872340 (-3125 3200);
DISPLAY INVISIBLE (-3125 3200);
FORCEPROP 1 LAST PATH I211
J 0
(-3452 3325);
DISPLAY 0.872340 (-3452 3325);
PAINT GREEN (-3452 3325);
DISPLAY INVISIBLE (-3452 3325);
FORCEADD TAP..1
(-3450 3275);
FORCEPROP 3 LASTPIN (-3500 3275) SIG_NAME M_B_CPU1_SB_DQ<17>
J 0
(-3490 3285);
DISPLAY 0.659574 (-3490 3285);
PAINT MONO (-3490 3285);
DISPLAY INVISIBLE (-3490 3285);
FORCEPROP 1 LASTPIN (-3500 3275) BN 17
J 0
(-3512 3283);
DISPLAY 0.489362 (-3512 3283);
PAINT GREEN (-3512 3283);
FORCEPROP 2 LAST CDS_LIB mstr_standard
J 0
(-3450 3275);
DISPLAY 0.723404 (-3450 3275);
PAINT MONO (-3450 3275);
DISPLAY INVISIBLE (-3450 3275);
FORCEPROP 1 LAST BODY_TYPE PLUMBING
J 0
(-3450 3325);
DISPLAY 0.872340 (-3450 3325);
PAINT GREEN (-3450 3325);
DISPLAY INVISIBLE (-3450 3325);
FORCEPROP 1 LAST HDL_TAP TRUE
J 0
(-3125 3150);
DISPLAY 0.872340 (-3125 3150);
DISPLAY INVISIBLE (-3125 3150);
FORCEPROP 1 LAST PATH I212
J 0
(-3452 3275);
DISPLAY 0.872340 (-3452 3275);
PAINT GREEN (-3452 3275);
DISPLAY INVISIBLE (-3452 3275);
FORCEADD TAP..1
(-3450 3225);
FORCEPROP 3 LASTPIN (-3500 3225) SIG_NAME M_B_CPU1_SB_DQ<18>
J 0
(-3490 3235);
DISPLAY 0.659574 (-3490 3235);
PAINT MONO (-3490 3235);
DISPLAY INVISIBLE (-3490 3235);
FORCEPROP 1 LASTPIN (-3500 3225) BN 18
J 0
(-3512 3233);
DISPLAY 0.489362 (-3512 3233);
PAINT GREEN (-3512 3233);
FORCEPROP 2 LAST CDS_LIB mstr_standard
J 0
(-3450 3225);
DISPLAY 0.723404 (-3450 3225);
PAINT MONO (-3450 3225);
DISPLAY INVISIBLE (-3450 3225);
FORCEPROP 1 LAST BODY_TYPE PLUMBING
J 0
(-3450 3275);
DISPLAY 0.872340 (-3450 3275);
PAINT GREEN (-3450 3275);
DISPLAY INVISIBLE (-3450 3275);
FORCEPROP 1 LAST HDL_TAP TRUE
J 0
(-3125 3100);
DISPLAY 0.872340 (-3125 3100);
DISPLAY INVISIBLE (-3125 3100);
FORCEPROP 1 LAST PATH I213
J 0
(-3452 3225);
DISPLAY 0.872340 (-3452 3225);
PAINT GREEN (-3452 3225);
DISPLAY INVISIBLE (-3452 3225);
FORCEADD TAP..1
(-3450 3075);
FORCEPROP 3 LASTPIN (-3500 3075) SIG_NAME M_B_CPU1_SB_DQ<21>
J 0
(-3490 3085);
DISPLAY 0.659574 (-3490 3085);
PAINT MONO (-3490 3085);
DISPLAY INVISIBLE (-3490 3085);
FORCEPROP 1 LASTPIN (-3500 3075) BN 21
J 0
(-3512 3083);
DISPLAY 0.489362 (-3512 3083);
PAINT GREEN (-3512 3083);
FORCEPROP 2 LAST CDS_LIB mstr_standard
J 0
(-3450 3075);
DISPLAY 0.723404 (-3450 3075);
PAINT MONO (-3450 3075);
DISPLAY INVISIBLE (-3450 3075);
FORCEPROP 1 LAST BODY_TYPE PLUMBING
J 0
(-3450 3125);
DISPLAY 0.872340 (-3450 3125);
PAINT GREEN (-3450 3125);
DISPLAY INVISIBLE (-3450 3125);
FORCEPROP 1 LAST HDL_TAP TRUE
J 0
(-3125 2950);
DISPLAY 0.872340 (-3125 2950);
DISPLAY INVISIBLE (-3125 2950);
FORCEPROP 1 LAST PATH I214
J 0
(-3452 3075);
DISPLAY 0.872340 (-3452 3075);
PAINT GREEN (-3452 3075);
DISPLAY INVISIBLE (-3452 3075);
FORCEADD TAP..1
(-3450 3125);
FORCEPROP 3 LASTPIN (-3500 3125) SIG_NAME M_B_CPU1_SB_DQ<20>
J 0
(-3490 3135);
DISPLAY 0.659574 (-3490 3135);
PAINT MONO (-3490 3135);
DISPLAY INVISIBLE (-3490 3135);
FORCEPROP 1 LASTPIN (-3500 3125) BN 20
J 0
(-3512 3133);
DISPLAY 0.489362 (-3512 3133);
PAINT GREEN (-3512 3133);
FORCEPROP 2 LAST CDS_LIB mstr_standard
J 0
(-3450 3125);
DISPLAY 0.723404 (-3450 3125);
PAINT MONO (-3450 3125);
DISPLAY INVISIBLE (-3450 3125);
FORCEPROP 1 LAST BODY_TYPE PLUMBING
J 0
(-3450 3175);
DISPLAY 0.872340 (-3450 3175);
PAINT GREEN (-3450 3175);
DISPLAY INVISIBLE (-3450 3175);
FORCEPROP 1 LAST HDL_TAP TRUE
J 0
(-3125 3000);
DISPLAY 0.872340 (-3125 3000);
DISPLAY INVISIBLE (-3125 3000);
FORCEPROP 1 LAST PATH I215
J 0
(-3452 3125);
DISPLAY 0.872340 (-3452 3125);
PAINT GREEN (-3452 3125);
DISPLAY INVISIBLE (-3452 3125);
FORCEADD TAP..1
(-3450 3175);
FORCEPROP 3 LASTPIN (-3500 3175) SIG_NAME M_B_CPU1_SB_DQ<19>
J 0
(-3490 3185);
DISPLAY 0.659574 (-3490 3185);
PAINT MONO (-3490 3185);
DISPLAY INVISIBLE (-3490 3185);
FORCEPROP 1 LASTPIN (-3500 3175) BN 19
J 0
(-3512 3183);
DISPLAY 0.489362 (-3512 3183);
PAINT GREEN (-3512 3183);
FORCEPROP 2 LAST CDS_LIB mstr_standard
J 0
(-3450 3175);
DISPLAY 0.723404 (-3450 3175);
PAINT MONO (-3450 3175);
DISPLAY INVISIBLE (-3450 3175);
FORCEPROP 1 LAST BODY_TYPE PLUMBING
J 0
(-3450 3225);
DISPLAY 0.872340 (-3450 3225);
PAINT GREEN (-3450 3225);
DISPLAY INVISIBLE (-3450 3225);
FORCEPROP 1 LAST HDL_TAP TRUE
J 0
(-3125 3050);
DISPLAY 0.872340 (-3125 3050);
DISPLAY INVISIBLE (-3125 3050);
FORCEPROP 1 LAST PATH I216
J 0
(-3452 3175);
DISPLAY 0.872340 (-3452 3175);
PAINT GREEN (-3452 3175);
DISPLAY INVISIBLE (-3452 3175);
FORCEADD TAP..1
(-3450 2825);
FORCEPROP 3 LASTPIN (-3500 2825) SIG_NAME M_B_CPU1_SB_DQ<25>
J 0
(-3490 2835);
DISPLAY 0.659574 (-3490 2835);
PAINT MONO (-3490 2835);
DISPLAY INVISIBLE (-3490 2835);
FORCEPROP 1 LASTPIN (-3500 2825) BN 25
J 0
(-3512 2833);
DISPLAY 0.489362 (-3512 2833);
PAINT GREEN (-3512 2833);
FORCEPROP 2 LAST CDS_LIB mstr_standard
J 0
(-3450 2825);
DISPLAY 0.723404 (-3450 2825);
PAINT MONO (-3450 2825);
DISPLAY INVISIBLE (-3450 2825);
FORCEPROP 1 LAST BODY_TYPE PLUMBING
J 0
(-3450 2875);
DISPLAY 0.872340 (-3450 2875);
PAINT GREEN (-3450 2875);
DISPLAY INVISIBLE (-3450 2875);
FORCEPROP 1 LAST HDL_TAP TRUE
J 0
(-3125 2700);
DISPLAY 0.872340 (-3125 2700);
DISPLAY INVISIBLE (-3125 2700);
FORCEPROP 1 LAST PATH I217
J 0
(-3452 2825);
DISPLAY 0.872340 (-3452 2825);
PAINT GREEN (-3452 2825);
DISPLAY INVISIBLE (-3452 2825);
FORCEADD TAP..1
(-3450 2875);
FORCEPROP 3 LASTPIN (-3500 2875) SIG_NAME M_B_CPU1_SB_DQ<24>
J 0
(-3490 2885);
DISPLAY 0.659574 (-3490 2885);
PAINT MONO (-3490 2885);
DISPLAY INVISIBLE (-3490 2885);
FORCEPROP 1 LASTPIN (-3500 2875) BN 24
J 0
(-3512 2883);
DISPLAY 0.489362 (-3512 2883);
PAINT GREEN (-3512 2883);
FORCEPROP 2 LAST CDS_LIB mstr_standard
J 0
(-3450 2875);
DISPLAY 0.723404 (-3450 2875);
PAINT MONO (-3450 2875);
DISPLAY INVISIBLE (-3450 2875);
FORCEPROP 1 LAST BODY_TYPE PLUMBING
J 0
(-3450 2925);
DISPLAY 0.872340 (-3450 2925);
PAINT GREEN (-3450 2925);
DISPLAY INVISIBLE (-3450 2925);
FORCEPROP 1 LAST HDL_TAP TRUE
J 0
(-3125 2750);
DISPLAY 0.872340 (-3125 2750);
DISPLAY INVISIBLE (-3125 2750);
FORCEPROP 1 LAST PATH I218
J 0
(-3452 2875);
DISPLAY 0.872340 (-3452 2875);
PAINT GREEN (-3452 2875);
DISPLAY INVISIBLE (-3452 2875);
FORCEADD TAP..1
(-3450 3025);
FORCEPROP 3 LASTPIN (-3500 3025) SIG_NAME M_B_CPU1_SB_DQ<22>
J 0
(-3490 3035);
DISPLAY 0.659574 (-3490 3035);
PAINT MONO (-3490 3035);
DISPLAY INVISIBLE (-3490 3035);
FORCEPROP 1 LASTPIN (-3500 3025) BN 22
J 0
(-3512 3033);
DISPLAY 0.489362 (-3512 3033);
PAINT GREEN (-3512 3033);
FORCEPROP 2 LAST CDS_LIB mstr_standard
J 0
(-3450 3025);
DISPLAY 0.723404 (-3450 3025);
PAINT MONO (-3450 3025);
DISPLAY INVISIBLE (-3450 3025);
FORCEPROP 1 LAST BODY_TYPE PLUMBING
J 0
(-3450 3075);
DISPLAY 0.872340 (-3450 3075);
PAINT GREEN (-3450 3075);
DISPLAY INVISIBLE (-3450 3075);
FORCEPROP 1 LAST HDL_TAP TRUE
J 0
(-3125 2900);
DISPLAY 0.872340 (-3125 2900);
DISPLAY INVISIBLE (-3125 2900);
FORCEPROP 1 LAST PATH I219
J 0
(-3452 3025);
DISPLAY 0.872340 (-3452 3025);
PAINT GREEN (-3452 3025);
DISPLAY INVISIBLE (-3452 3025);
FORCEADD TAP..1
(-3450 2975);
FORCEPROP 3 LASTPIN (-3500 2975) SIG_NAME M_B_CPU1_SB_DQ<23>
J 0
(-3490 2985);
DISPLAY 0.659574 (-3490 2985);
PAINT MONO (-3490 2985);
DISPLAY INVISIBLE (-3490 2985);
FORCEPROP 1 LASTPIN (-3500 2975) BN 23
J 0
(-3512 2983);
DISPLAY 0.489362 (-3512 2983);
PAINT GREEN (-3512 2983);
FORCEPROP 2 LAST CDS_LIB mstr_standard
J 0
(-3450 2975);
DISPLAY 0.723404 (-3450 2975);
PAINT MONO (-3450 2975);
DISPLAY INVISIBLE (-3450 2975);
FORCEPROP 1 LAST BODY_TYPE PLUMBING
J 0
(-3450 3025);
DISPLAY 0.872340 (-3450 3025);
PAINT GREEN (-3450 3025);
DISPLAY INVISIBLE (-3450 3025);
FORCEPROP 1 LAST HDL_TAP TRUE
J 0
(-3125 2850);
DISPLAY 0.872340 (-3125 2850);
DISPLAY INVISIBLE (-3125 2850);
FORCEPROP 1 LAST PATH I220
J 0
(-3452 2975);
DISPLAY 0.872340 (-3452 2975);
PAINT GREEN (-3452 2975);
DISPLAY INVISIBLE (-3452 2975);
FORCEADD TAP..1
(-3450 2575);
FORCEPROP 3 LASTPIN (-3500 2575) SIG_NAME M_B_CPU1_SB_DQ<30>
J 0
(-3490 2585);
DISPLAY 0.659574 (-3490 2585);
PAINT MONO (-3490 2585);
DISPLAY INVISIBLE (-3490 2585);
FORCEPROP 1 LASTPIN (-3500 2575) BN 30
J 0
(-3512 2583);
DISPLAY 0.489362 (-3512 2583);
PAINT GREEN (-3512 2583);
FORCEPROP 2 LAST CDS_LIB mstr_standard
J 0
(-3450 2575);
DISPLAY 0.723404 (-3450 2575);
PAINT MONO (-3450 2575);
DISPLAY INVISIBLE (-3450 2575);
FORCEPROP 1 LAST BODY_TYPE PLUMBING
J 0
(-3450 2625);
DISPLAY 0.872340 (-3450 2625);
PAINT GREEN (-3450 2625);
DISPLAY INVISIBLE (-3450 2625);
FORCEPROP 1 LAST HDL_TAP TRUE
J 0
(-3125 2450);
DISPLAY 0.872340 (-3125 2450);
DISPLAY INVISIBLE (-3125 2450);
FORCEPROP 1 LAST PATH I221
J 0
(-3452 2575);
DISPLAY 0.872340 (-3452 2575);
PAINT GREEN (-3452 2575);
DISPLAY INVISIBLE (-3452 2575);
FORCEADD TAP..1
(-3450 2625);
FORCEPROP 3 LASTPIN (-3500 2625) SIG_NAME M_B_CPU1_SB_DQ<29>
J 0
(-3490 2635);
DISPLAY 0.659574 (-3490 2635);
PAINT MONO (-3490 2635);
DISPLAY INVISIBLE (-3490 2635);
FORCEPROP 1 LASTPIN (-3500 2625) BN 29
J 0
(-3512 2633);
DISPLAY 0.489362 (-3512 2633);
PAINT GREEN (-3512 2633);
FORCEPROP 2 LAST CDS_LIB mstr_standard
J 0
(-3450 2625);
DISPLAY 0.723404 (-3450 2625);
PAINT MONO (-3450 2625);
DISPLAY INVISIBLE (-3450 2625);
FORCEPROP 1 LAST BODY_TYPE PLUMBING
J 0
(-3450 2675);
DISPLAY 0.872340 (-3450 2675);
PAINT GREEN (-3450 2675);
DISPLAY INVISIBLE (-3450 2675);
FORCEPROP 1 LAST HDL_TAP TRUE
J 0
(-3125 2500);
DISPLAY 0.872340 (-3125 2500);
DISPLAY INVISIBLE (-3125 2500);
FORCEPROP 1 LAST PATH I222
J 0
(-3452 2625);
DISPLAY 0.872340 (-3452 2625);
PAINT GREEN (-3452 2625);
DISPLAY INVISIBLE (-3452 2625);
FORCEADD TAP..1
(-3450 2675);
FORCEPROP 3 LASTPIN (-3500 2675) SIG_NAME M_B_CPU1_SB_DQ<28>
J 0
(-3490 2685);
DISPLAY 0.659574 (-3490 2685);
PAINT MONO (-3490 2685);
DISPLAY INVISIBLE (-3490 2685);
FORCEPROP 1 LASTPIN (-3500 2675) BN 28
J 0
(-3512 2683);
DISPLAY 0.489362 (-3512 2683);
PAINT GREEN (-3512 2683);
FORCEPROP 2 LAST CDS_LIB mstr_standard
J 0
(-3450 2675);
DISPLAY 0.723404 (-3450 2675);
PAINT MONO (-3450 2675);
DISPLAY INVISIBLE (-3450 2675);
FORCEPROP 1 LAST BODY_TYPE PLUMBING
J 0
(-3450 2725);
DISPLAY 0.872340 (-3450 2725);
PAINT GREEN (-3450 2725);
DISPLAY INVISIBLE (-3450 2725);
FORCEPROP 1 LAST HDL_TAP TRUE
J 0
(-3125 2550);
DISPLAY 0.872340 (-3125 2550);
DISPLAY INVISIBLE (-3125 2550);
FORCEPROP 1 LAST PATH I223
J 0
(-3452 2675);
DISPLAY 0.872340 (-3452 2675);
PAINT GREEN (-3452 2675);
DISPLAY INVISIBLE (-3452 2675);
FORCEADD TAP..1
(-3450 2725);
FORCEPROP 3 LASTPIN (-3500 2725) SIG_NAME M_B_CPU1_SB_DQ<27>
J 0
(-3490 2735);
DISPLAY 0.659574 (-3490 2735);
PAINT MONO (-3490 2735);
DISPLAY INVISIBLE (-3490 2735);
FORCEPROP 1 LASTPIN (-3500 2725) BN 27
J 0
(-3512 2733);
DISPLAY 0.489362 (-3512 2733);
PAINT GREEN (-3512 2733);
FORCEPROP 2 LAST CDS_LIB mstr_standard
J 0
(-3450 2725);
DISPLAY 0.723404 (-3450 2725);
PAINT MONO (-3450 2725);
DISPLAY INVISIBLE (-3450 2725);
FORCEPROP 1 LAST BODY_TYPE PLUMBING
J 0
(-3450 2775);
DISPLAY 0.872340 (-3450 2775);
PAINT GREEN (-3450 2775);
DISPLAY INVISIBLE (-3450 2775);
FORCEPROP 1 LAST HDL_TAP TRUE
J 0
(-3125 2600);
DISPLAY 0.872340 (-3125 2600);
DISPLAY INVISIBLE (-3125 2600);
FORCEPROP 1 LAST PATH I224
J 0
(-3452 2725);
DISPLAY 0.872340 (-3452 2725);
PAINT GREEN (-3452 2725);
DISPLAY INVISIBLE (-3452 2725);
FORCEADD TAP..1
(-3450 2775);
FORCEPROP 3 LASTPIN (-3500 2775) SIG_NAME M_B_CPU1_SB_DQ<26>
J 0
(-3490 2785);
DISPLAY 0.659574 (-3490 2785);
PAINT MONO (-3490 2785);
DISPLAY INVISIBLE (-3490 2785);
FORCEPROP 1 LASTPIN (-3500 2775) BN 26
J 0
(-3512 2783);
DISPLAY 0.489362 (-3512 2783);
PAINT GREEN (-3512 2783);
FORCEPROP 2 LAST CDS_LIB mstr_standard
J 0
(-3450 2775);
DISPLAY 0.723404 (-3450 2775);
PAINT MONO (-3450 2775);
DISPLAY INVISIBLE (-3450 2775);
FORCEPROP 1 LAST BODY_TYPE PLUMBING
J 0
(-3450 2825);
DISPLAY 0.872340 (-3450 2825);
PAINT GREEN (-3450 2825);
DISPLAY INVISIBLE (-3450 2825);
FORCEPROP 1 LAST HDL_TAP TRUE
J 0
(-3125 2650);
DISPLAY 0.872340 (-3125 2650);
DISPLAY INVISIBLE (-3125 2650);
FORCEPROP 1 LAST PATH I225
J 0
(-3452 2775);
DISPLAY 0.872340 (-3452 2775);
PAINT GREEN (-3452 2775);
DISPLAY INVISIBLE (-3452 2775);
FORCEADD TAP..1
(-3450 2325);
FORCEPROP 3 LASTPIN (-3500 2325) SIG_NAME M_B_CPU1_SA_CB<2>
J 0
(-3490 2335);
DISPLAY 0.659574 (-3490 2335);
PAINT MONO (-3490 2335);
DISPLAY INVISIBLE (-3490 2335);
FORCEPROP 1 LASTPIN (-3500 2325) BN 2
J 0
(-3512 2333);
DISPLAY 0.489362 (-3512 2333);
PAINT GREEN (-3512 2333);
FORCEPROP 2 LAST CDS_LIB mstr_standard
J 2
(-3450 2325);
DISPLAY 0.723404 (-3450 2325);
PAINT MONO (-3450 2325);
DISPLAY INVISIBLE (-3450 2325);
FORCEPROP 1 LAST BODY_TYPE PLUMBING
J 0
(-3450 2375);
DISPLAY 0.872340 (-3450 2375);
PAINT GREEN (-3450 2375);
DISPLAY INVISIBLE (-3450 2375);
FORCEPROP 1 LAST HDL_TAP TRUE
J 0
(-3125 2200);
DISPLAY 0.872340 (-3125 2200);
DISPLAY INVISIBLE (-3125 2200);
FORCEPROP 1 LAST PATH I226
J 0
(-3452 2325);
DISPLAY 0.872340 (-3452 2325);
PAINT GREEN (-3452 2325);
DISPLAY INVISIBLE (-3452 2325);
FORCEADD TAP..1
(-3450 2375);
FORCEPROP 3 LASTPIN (-3500 2375) SIG_NAME M_B_CPU1_SA_CB<1>
J 0
(-3490 2385);
DISPLAY 0.659574 (-3490 2385);
PAINT MONO (-3490 2385);
DISPLAY INVISIBLE (-3490 2385);
FORCEPROP 1 LASTPIN (-3500 2375) BN 1
J 0
(-3512 2383);
DISPLAY 0.489362 (-3512 2383);
PAINT GREEN (-3512 2383);
FORCEPROP 2 LAST CDS_LIB mstr_standard
J 2
(-3450 2375);
DISPLAY 0.723404 (-3450 2375);
PAINT MONO (-3450 2375);
DISPLAY INVISIBLE (-3450 2375);
FORCEPROP 1 LAST BODY_TYPE PLUMBING
J 0
(-3450 2425);
DISPLAY 0.872340 (-3450 2425);
PAINT GREEN (-3450 2425);
DISPLAY INVISIBLE (-3450 2425);
FORCEPROP 1 LAST HDL_TAP TRUE
J 0
(-3125 2250);
DISPLAY 0.872340 (-3125 2250);
DISPLAY INVISIBLE (-3125 2250);
FORCEPROP 1 LAST PATH I227
J 0
(-3452 2375);
DISPLAY 0.872340 (-3452 2375);
PAINT GREEN (-3452 2375);
DISPLAY INVISIBLE (-3452 2375);
FORCEADD TAP..1
(-3450 2425);
FORCEPROP 3 LASTPIN (-3500 2425) SIG_NAME M_B_CPU1_SA_CB<0>
J 0
(-3490 2435);
DISPLAY 0.659574 (-3490 2435);
PAINT MONO (-3490 2435);
DISPLAY INVISIBLE (-3490 2435);
FORCEPROP 1 LASTPIN (-3500 2425) BN 0
J 0
(-3512 2433);
DISPLAY 0.489362 (-3512 2433);
PAINT GREEN (-3512 2433);
FORCEPROP 2 LAST CDS_LIB mstr_standard
J 2
(-3450 2425);
DISPLAY 0.723404 (-3450 2425);
PAINT MONO (-3450 2425);
DISPLAY INVISIBLE (-3450 2425);
FORCEPROP 1 LAST BODY_TYPE PLUMBING
J 0
(-3450 2475);
DISPLAY 0.872340 (-3450 2475);
PAINT GREEN (-3450 2475);
DISPLAY INVISIBLE (-3450 2475);
FORCEPROP 1 LAST HDL_TAP TRUE
J 0
(-3125 2300);
DISPLAY 0.872340 (-3125 2300);
DISPLAY INVISIBLE (-3125 2300);
FORCEPROP 1 LAST PATH I228
J 0
(-3452 2425);
DISPLAY 0.872340 (-3452 2425);
PAINT GREEN (-3452 2425);
DISPLAY INVISIBLE (-3452 2425);
FORCEADD TAP..1
(-3450 2525);
FORCEPROP 3 LASTPIN (-3500 2525) SIG_NAME M_B_CPU1_SB_DQ<31>
J 0
(-3490 2535);
DISPLAY 0.659574 (-3490 2535);
PAINT MONO (-3490 2535);
DISPLAY INVISIBLE (-3490 2535);
FORCEPROP 1 LASTPIN (-3500 2525) BN 31
J 0
(-3512 2533);
DISPLAY 0.489362 (-3512 2533);
PAINT GREEN (-3512 2533);
FORCEPROP 2 LAST CDS_LIB mstr_standard
J 0
(-3450 2525);
DISPLAY 0.723404 (-3450 2525);
PAINT MONO (-3450 2525);
DISPLAY INVISIBLE (-3450 2525);
FORCEPROP 1 LAST BODY_TYPE PLUMBING
J 0
(-3450 2575);
DISPLAY 0.872340 (-3450 2575);
PAINT GREEN (-3450 2575);
DISPLAY INVISIBLE (-3450 2575);
FORCEPROP 1 LAST HDL_TAP TRUE
J 0
(-3125 2400);
DISPLAY 0.872340 (-3125 2400);
DISPLAY INVISIBLE (-3125 2400);
FORCEPROP 1 LAST PATH I229
J 0
(-3452 2525);
DISPLAY 0.872340 (-3452 2525);
PAINT GREEN (-3452 2525);
DISPLAY INVISIBLE (-3452 2525);
FORCEADD TAP..1
(-3450 2275);
FORCEPROP 3 LASTPIN (-3500 2275) SIG_NAME M_B_CPU1_SA_CB<3>
J 0
(-3490 2285);
DISPLAY 0.659574 (-3490 2285);
PAINT MONO (-3490 2285);
DISPLAY INVISIBLE (-3490 2285);
FORCEPROP 1 LASTPIN (-3500 2275) BN 3
J 0
(-3512 2283);
DISPLAY 0.489362 (-3512 2283);
PAINT GREEN (-3512 2283);
FORCEPROP 2 LAST CDS_LIB mstr_standard
J 2
(-3450 2275);
DISPLAY 0.723404 (-3450 2275);
PAINT MONO (-3450 2275);
DISPLAY INVISIBLE (-3450 2275);
FORCEPROP 1 LAST BODY_TYPE PLUMBING
J 0
(-3450 2325);
DISPLAY 0.872340 (-3450 2325);
PAINT GREEN (-3450 2325);
DISPLAY INVISIBLE (-3450 2325);
FORCEPROP 1 LAST HDL_TAP TRUE
J 0
(-3125 2150);
DISPLAY 0.872340 (-3125 2150);
DISPLAY INVISIBLE (-3125 2150);
FORCEPROP 1 LAST PATH I230
J 0
(-3452 2275);
DISPLAY 0.872340 (-3452 2275);
PAINT GREEN (-3452 2275);
DISPLAY INVISIBLE (-3452 2275);
FORCEADD TAP..1
(-3450 2225);
FORCEPROP 3 LASTPIN (-3500 2225) SIG_NAME M_B_CPU1_SA_CB<4>
J 0
(-3490 2235);
DISPLAY 0.659574 (-3490 2235);
PAINT MONO (-3490 2235);
DISPLAY INVISIBLE (-3490 2235);
FORCEPROP 1 LASTPIN (-3500 2225) BN 4
J 0
(-3512 2233);
DISPLAY 0.489362 (-3512 2233);
PAINT GREEN (-3512 2233);
FORCEPROP 2 LAST CDS_LIB mstr_standard
J 2
(-3450 2225);
DISPLAY 0.723404 (-3450 2225);
PAINT MONO (-3450 2225);
DISPLAY INVISIBLE (-3450 2225);
FORCEPROP 1 LAST BODY_TYPE PLUMBING
J 0
(-3450 2275);
DISPLAY 0.872340 (-3450 2275);
PAINT GREEN (-3450 2275);
DISPLAY INVISIBLE (-3450 2275);
FORCEPROP 1 LAST HDL_TAP TRUE
J 0
(-3125 2100);
DISPLAY 0.872340 (-3125 2100);
DISPLAY INVISIBLE (-3125 2100);
FORCEPROP 1 LAST PATH I231
J 0
(-3452 2225);
DISPLAY 0.872340 (-3452 2225);
PAINT GREEN (-3452 2225);
DISPLAY INVISIBLE (-3452 2225);
FORCEADD TAP..1
(-3450 2175);
FORCEPROP 3 LASTPIN (-3500 2175) SIG_NAME M_B_CPU1_SA_CB<5>
J 0
(-3490 2185);
DISPLAY 0.659574 (-3490 2185);
PAINT MONO (-3490 2185);
DISPLAY INVISIBLE (-3490 2185);
FORCEPROP 1 LASTPIN (-3500 2175) BN 5
J 0
(-3512 2183);
DISPLAY 0.489362 (-3512 2183);
PAINT GREEN (-3512 2183);
FORCEPROP 2 LAST CDS_LIB mstr_standard
J 2
(-3450 2175);
DISPLAY 0.723404 (-3450 2175);
PAINT MONO (-3450 2175);
DISPLAY INVISIBLE (-3450 2175);
FORCEPROP 1 LAST BODY_TYPE PLUMBING
J 0
(-3450 2225);
DISPLAY 0.872340 (-3450 2225);
PAINT GREEN (-3450 2225);
DISPLAY INVISIBLE (-3450 2225);
FORCEPROP 1 LAST HDL_TAP TRUE
J 0
(-3125 2050);
DISPLAY 0.872340 (-3125 2050);
DISPLAY INVISIBLE (-3125 2050);
FORCEPROP 1 LAST PATH I232
J 0
(-3452 2175);
DISPLAY 0.872340 (-3452 2175);
PAINT GREEN (-3452 2175);
DISPLAY INVISIBLE (-3452 2175);
FORCEADD TAP..1
(-3450 2075);
FORCEPROP 3 LASTPIN (-3500 2075) SIG_NAME M_B_CPU1_SA_CB<7>
J 0
(-3490 2085);
DISPLAY 0.659574 (-3490 2085);
PAINT MONO (-3490 2085);
DISPLAY INVISIBLE (-3490 2085);
FORCEPROP 1 LASTPIN (-3500 2075) BN 7
J 0
(-3512 2083);
DISPLAY 0.489362 (-3512 2083);
PAINT GREEN (-3512 2083);
FORCEPROP 2 LAST CDS_LIB mstr_standard
J 2
(-3450 2075);
DISPLAY 0.723404 (-3450 2075);
PAINT MONO (-3450 2075);
DISPLAY INVISIBLE (-3450 2075);
FORCEPROP 1 LAST BODY_TYPE PLUMBING
J 0
(-3450 2125);
DISPLAY 0.872340 (-3450 2125);
PAINT GREEN (-3450 2125);
DISPLAY INVISIBLE (-3450 2125);
FORCEPROP 1 LAST HDL_TAP TRUE
J 0
(-3125 1950);
DISPLAY 0.872340 (-3125 1950);
DISPLAY INVISIBLE (-3125 1950);
FORCEPROP 1 LAST PATH I233
J 0
(-3452 2075);
DISPLAY 0.872340 (-3452 2075);
PAINT GREEN (-3452 2075);
DISPLAY INVISIBLE (-3452 2075);
FORCEADD TAP..1
(-3450 2125);
FORCEPROP 3 LASTPIN (-3500 2125) SIG_NAME M_B_CPU1_SA_CB<6>
J 0
(-3490 2135);
DISPLAY 0.659574 (-3490 2135);
PAINT MONO (-3490 2135);
DISPLAY INVISIBLE (-3490 2135);
FORCEPROP 1 LASTPIN (-3500 2125) BN 6
J 0
(-3512 2133);
DISPLAY 0.489362 (-3512 2133);
PAINT GREEN (-3512 2133);
FORCEPROP 2 LAST CDS_LIB mstr_standard
J 2
(-3450 2125);
DISPLAY 0.723404 (-3450 2125);
PAINT MONO (-3450 2125);
DISPLAY INVISIBLE (-3450 2125);
FORCEPROP 1 LAST BODY_TYPE PLUMBING
J 0
(-3450 2175);
DISPLAY 0.872340 (-3450 2175);
PAINT GREEN (-3450 2175);
DISPLAY INVISIBLE (-3450 2175);
FORCEPROP 1 LAST HDL_TAP TRUE
J 0
(-3125 2000);
DISPLAY 0.872340 (-3125 2000);
DISPLAY INVISIBLE (-3125 2000);
FORCEPROP 1 LAST PATH I234
J 0
(-3452 2125);
DISPLAY 0.872340 (-3452 2125);
PAINT GREEN (-3452 2125);
DISPLAY INVISIBLE (-3452 2125);
FORCEADD OFFPAGE..6
R 2
(-2850 2025);
FORCEPROP 2 LAST $XR0 98 
J 0
(-2636 2025);
DISPLAY 0.638298 (-2636 2025);
PAINT MONO (-2636 2025);
FORCEPROP 2 LAST PATH I235
J 0
(-2625 2075);
DISPLAY 1.021277 (-2625 2075);
DISPLAY INVISIBLE (-2625 2075);
FORCEPROP 1 LAST COMMENT_BODY TRUE
J 2
(-2950 1950);
DISPLAY 0.872340 (-2950 1950);
PAINT GREEN (-2950 1950);
DISPLAY INVISIBLE (-2950 1950);
FORCEPROP 1 LAST OFFPAGE TRUE
J 2
(-3175 1900);
DISPLAY 0.872340 (-3175 1900);
PAINT GREEN (-3175 1900);
DISPLAY INVISIBLE (-3175 1900);
FORCEPROP 2 LAST CDS_LIB mstr_standard
J 2
(-2850 2025);
DISPLAY 0.723404 (-2850 2025);
PAINT MONO (-2850 2025);
DISPLAY INVISIBLE (-2850 2025);
FORCEADD TAP..1
(-3450 1975);
FORCEPROP 3 LASTPIN (-3500 1975) SIG_NAME M_B_CPU1_SB_CB<0>
J 0
(-3490 1985);
DISPLAY 0.659574 (-3490 1985);
PAINT MONO (-3490 1985);
DISPLAY INVISIBLE (-3490 1985);
FORCEPROP 1 LASTPIN (-3500 1975) BN 0
J 0
(-3512 1983);
DISPLAY 0.489362 (-3512 1983);
PAINT GREEN (-3512 1983);
FORCEPROP 2 LAST CDS_LIB mstr_standard
J 2
(-3450 1975);
DISPLAY 0.723404 (-3450 1975);
PAINT MONO (-3450 1975);
DISPLAY INVISIBLE (-3450 1975);
FORCEPROP 1 LAST BODY_TYPE PLUMBING
J 0
(-3450 2025);
DISPLAY 0.872340 (-3450 2025);
PAINT GREEN (-3450 2025);
DISPLAY INVISIBLE (-3450 2025);
FORCEPROP 1 LAST HDL_TAP TRUE
J 0
(-3125 1850);
DISPLAY 0.872340 (-3125 1850);
DISPLAY INVISIBLE (-3125 1850);
FORCEPROP 1 LAST PATH I236
J 0
(-3452 1975);
DISPLAY 0.872340 (-3452 1975);
PAINT GREEN (-3452 1975);
DISPLAY INVISIBLE (-3452 1975);
FORCEADD TAP..1
(-3450 1925);
FORCEPROP 3 LASTPIN (-3500 1925) SIG_NAME M_B_CPU1_SB_CB<1>
J 0
(-3490 1935);
DISPLAY 0.659574 (-3490 1935);
PAINT MONO (-3490 1935);
DISPLAY INVISIBLE (-3490 1935);
FORCEPROP 1 LASTPIN (-3500 1925) BN 1
J 0
(-3512 1933);
DISPLAY 0.489362 (-3512 1933);
PAINT GREEN (-3512 1933);
FORCEPROP 2 LAST CDS_LIB mstr_standard
J 2
(-3450 1925);
DISPLAY 0.723404 (-3450 1925);
PAINT MONO (-3450 1925);
DISPLAY INVISIBLE (-3450 1925);
FORCEPROP 1 LAST BODY_TYPE PLUMBING
J 0
(-3450 1975);
DISPLAY 0.872340 (-3450 1975);
PAINT GREEN (-3450 1975);
DISPLAY INVISIBLE (-3450 1975);
FORCEPROP 1 LAST HDL_TAP TRUE
J 0
(-3125 1800);
DISPLAY 0.872340 (-3125 1800);
DISPLAY INVISIBLE (-3125 1800);
FORCEPROP 1 LAST PATH I237
J 0
(-3452 1925);
DISPLAY 0.872340 (-3452 1925);
PAINT GREEN (-3452 1925);
DISPLAY INVISIBLE (-3452 1925);
FORCEADD TAP..1
(-3450 1875);
FORCEPROP 3 LASTPIN (-3500 1875) SIG_NAME M_B_CPU1_SB_CB<2>
J 0
(-3490 1885);
DISPLAY 0.659574 (-3490 1885);
PAINT MONO (-3490 1885);
DISPLAY INVISIBLE (-3490 1885);
FORCEPROP 1 LASTPIN (-3500 1875) BN 2
J 0
(-3512 1883);
DISPLAY 0.489362 (-3512 1883);
PAINT GREEN (-3512 1883);
FORCEPROP 2 LAST CDS_LIB mstr_standard
J 2
(-3450 1875);
DISPLAY 0.723404 (-3450 1875);
PAINT MONO (-3450 1875);
DISPLAY INVISIBLE (-3450 1875);
FORCEPROP 1 LAST BODY_TYPE PLUMBING
J 0
(-3450 1925);
DISPLAY 0.872340 (-3450 1925);
PAINT GREEN (-3450 1925);
DISPLAY INVISIBLE (-3450 1925);
FORCEPROP 1 LAST HDL_TAP TRUE
J 0
(-3125 1750);
DISPLAY 0.872340 (-3125 1750);
DISPLAY INVISIBLE (-3125 1750);
FORCEPROP 1 LAST PATH I238
J 0
(-3452 1875);
DISPLAY 0.872340 (-3452 1875);
PAINT GREEN (-3452 1875);
DISPLAY INVISIBLE (-3452 1875);
FORCEADD TAP..1
(-3450 1825);
FORCEPROP 3 LASTPIN (-3500 1825) SIG_NAME M_B_CPU1_SB_CB<3>
J 0
(-3490 1835);
DISPLAY 0.659574 (-3490 1835);
PAINT MONO (-3490 1835);
DISPLAY INVISIBLE (-3490 1835);
FORCEPROP 1 LASTPIN (-3500 1825) BN 3
J 0
(-3512 1833);
DISPLAY 0.489362 (-3512 1833);
PAINT GREEN (-3512 1833);
FORCEPROP 2 LAST CDS_LIB mstr_standard
J 2
(-3450 1825);
DISPLAY 0.723404 (-3450 1825);
PAINT MONO (-3450 1825);
DISPLAY INVISIBLE (-3450 1825);
FORCEPROP 1 LAST BODY_TYPE PLUMBING
J 0
(-3450 1875);
DISPLAY 0.872340 (-3450 1875);
PAINT GREEN (-3450 1875);
DISPLAY INVISIBLE (-3450 1875);
FORCEPROP 1 LAST HDL_TAP TRUE
J 0
(-3125 1700);
DISPLAY 0.872340 (-3125 1700);
DISPLAY INVISIBLE (-3125 1700);
FORCEPROP 1 LAST PATH I239
J 0
(-3452 1825);
DISPLAY 0.872340 (-3452 1825);
PAINT GREEN (-3452 1825);
DISPLAY INVISIBLE (-3452 1825);
FORCEADD TAP..1
(-3450 1775);
FORCEPROP 3 LASTPIN (-3500 1775) SIG_NAME M_B_CPU1_SB_CB<4>
J 0
(-3490 1785);
DISPLAY 0.659574 (-3490 1785);
PAINT MONO (-3490 1785);
DISPLAY INVISIBLE (-3490 1785);
FORCEPROP 1 LASTPIN (-3500 1775) BN 4
J 0
(-3512 1783);
DISPLAY 0.489362 (-3512 1783);
PAINT GREEN (-3512 1783);
FORCEPROP 2 LAST CDS_LIB mstr_standard
J 2
(-3450 1775);
DISPLAY 0.723404 (-3450 1775);
PAINT MONO (-3450 1775);
DISPLAY INVISIBLE (-3450 1775);
FORCEPROP 1 LAST BODY_TYPE PLUMBING
J 0
(-3450 1825);
DISPLAY 0.872340 (-3450 1825);
PAINT GREEN (-3450 1825);
DISPLAY INVISIBLE (-3450 1825);
FORCEPROP 1 LAST HDL_TAP TRUE
J 0
(-3125 1650);
DISPLAY 0.872340 (-3125 1650);
DISPLAY INVISIBLE (-3125 1650);
FORCEPROP 1 LAST PATH I240
J 0
(-3452 1775);
DISPLAY 0.872340 (-3452 1775);
PAINT GREEN (-3452 1775);
DISPLAY INVISIBLE (-3452 1775);
FORCEADD TAP..1
(-3450 1725);
FORCEPROP 3 LASTPIN (-3500 1725) SIG_NAME M_B_CPU1_SB_CB<5>
J 0
(-3490 1735);
DISPLAY 0.659574 (-3490 1735);
PAINT MONO (-3490 1735);
DISPLAY INVISIBLE (-3490 1735);
FORCEPROP 1 LASTPIN (-3500 1725) BN 5
J 0
(-3512 1733);
DISPLAY 0.489362 (-3512 1733);
PAINT GREEN (-3512 1733);
FORCEPROP 2 LAST CDS_LIB mstr_standard
J 2
(-3450 1725);
DISPLAY 0.723404 (-3450 1725);
PAINT MONO (-3450 1725);
DISPLAY INVISIBLE (-3450 1725);
FORCEPROP 1 LAST BODY_TYPE PLUMBING
J 0
(-3450 1775);
DISPLAY 0.872340 (-3450 1775);
PAINT GREEN (-3450 1775);
DISPLAY INVISIBLE (-3450 1775);
FORCEPROP 1 LAST HDL_TAP TRUE
J 0
(-3125 1600);
DISPLAY 0.872340 (-3125 1600);
DISPLAY INVISIBLE (-3125 1600);
FORCEPROP 1 LAST PATH I241
J 0
(-3452 1725);
DISPLAY 0.872340 (-3452 1725);
PAINT GREEN (-3452 1725);
DISPLAY INVISIBLE (-3452 1725);
FORCEADD TAP..1
(-3450 1625);
FORCEPROP 3 LASTPIN (-3500 1625) SIG_NAME M_B_CPU1_SB_CB<7>
J 0
(-3490 1635);
DISPLAY 0.659574 (-3490 1635);
PAINT MONO (-3490 1635);
DISPLAY INVISIBLE (-3490 1635);
FORCEPROP 1 LASTPIN (-3500 1625) BN 7
J 0
(-3512 1633);
DISPLAY 0.489362 (-3512 1633);
PAINT GREEN (-3512 1633);
FORCEPROP 2 LAST CDS_LIB mstr_standard
J 2
(-3450 1625);
DISPLAY 0.723404 (-3450 1625);
PAINT MONO (-3450 1625);
DISPLAY INVISIBLE (-3450 1625);
FORCEPROP 1 LAST BODY_TYPE PLUMBING
J 0
(-3450 1675);
DISPLAY 0.872340 (-3450 1675);
PAINT GREEN (-3450 1675);
DISPLAY INVISIBLE (-3450 1675);
FORCEPROP 1 LAST HDL_TAP TRUE
J 0
(-3125 1500);
DISPLAY 0.872340 (-3125 1500);
DISPLAY INVISIBLE (-3125 1500);
FORCEPROP 1 LAST PATH I242
J 0
(-3452 1625);
DISPLAY 0.872340 (-3452 1625);
PAINT GREEN (-3452 1625);
DISPLAY INVISIBLE (-3452 1625);
FORCEADD TAP..1
(-3450 1675);
FORCEPROP 3 LASTPIN (-3500 1675) SIG_NAME M_B_CPU1_SB_CB<6>
J 0
(-3490 1685);
DISPLAY 0.659574 (-3490 1685);
PAINT MONO (-3490 1685);
DISPLAY INVISIBLE (-3490 1685);
FORCEPROP 1 LASTPIN (-3500 1675) BN 6
J 0
(-3512 1683);
DISPLAY 0.489362 (-3512 1683);
PAINT GREEN (-3512 1683);
FORCEPROP 2 LAST CDS_LIB mstr_standard
J 2
(-3450 1675);
DISPLAY 0.723404 (-3450 1675);
PAINT MONO (-3450 1675);
DISPLAY INVISIBLE (-3450 1675);
FORCEPROP 1 LAST BODY_TYPE PLUMBING
J 0
(-3450 1725);
DISPLAY 0.872340 (-3450 1725);
PAINT GREEN (-3450 1725);
DISPLAY INVISIBLE (-3450 1725);
FORCEPROP 1 LAST HDL_TAP TRUE
J 0
(-3125 1550);
DISPLAY 0.872340 (-3125 1550);
DISPLAY INVISIBLE (-3125 1550);
FORCEPROP 1 LAST PATH I243
J 0
(-3452 1675);
DISPLAY 0.872340 (-3452 1675);
PAINT GREEN (-3452 1675);
DISPLAY INVISIBLE (-3452 1675);
FORCEADD TAP..1
R 2
(-5875 6025);
FORCEPROP 3 LASTPIN (-5825 6025) SIG_NAME M_B_CPU1_SA_DQS_DP<0>
J 0
(-5815 6035);
DISPLAY 0.659574 (-5815 6035);
PAINT MONO (-5815 6035);
DISPLAY INVISIBLE (-5815 6035);
FORCEPROP 1 LASTPIN (-5825 6025) BN 0
J 2
(-5813 6033);
DISPLAY 0.489362 (-5813 6033);
PAINT GREEN (-5813 6033);
FORCEPROP 2 LAST CDS_LIB mstr_standard
J 2
(-5875 6025);
DISPLAY 0.723404 (-5875 6025);
PAINT MONO (-5875 6025);
DISPLAY INVISIBLE (-5875 6025);
FORCEPROP 1 LAST BODY_TYPE PLUMBING
J 2
(-5875 6075);
DISPLAY 0.872340 (-5875 6075);
PAINT GREEN (-5875 6075);
DISPLAY INVISIBLE (-5875 6075);
FORCEPROP 1 LAST HDL_TAP TRUE
J 2
(-6200 5900);
DISPLAY 0.872340 (-6200 5900);
DISPLAY INVISIBLE (-6200 5900);
FORCEPROP 1 LAST PATH I244
J 2
(-5873 6025);
DISPLAY 0.872340 (-5873 6025);
PAINT GREEN (-5873 6025);
DISPLAY INVISIBLE (-5873 6025);
FORCEADD TAP..1
R 2
(-5875 5925);
FORCEPROP 3 LASTPIN (-5825 5925) SIG_NAME M_B_CPU1_SA_DQS_DP<1>
J 0
(-5815 5935);
DISPLAY 0.659574 (-5815 5935);
PAINT MONO (-5815 5935);
DISPLAY INVISIBLE (-5815 5935);
FORCEPROP 1 LASTPIN (-5825 5925) BN 1
J 2
(-5813 5933);
DISPLAY 0.489362 (-5813 5933);
PAINT GREEN (-5813 5933);
FORCEPROP 2 LAST CDS_LIB mstr_standard
J 2
(-5875 5925);
DISPLAY 0.723404 (-5875 5925);
PAINT MONO (-5875 5925);
DISPLAY INVISIBLE (-5875 5925);
FORCEPROP 1 LAST BODY_TYPE PLUMBING
J 2
(-5875 5975);
DISPLAY 0.872340 (-5875 5975);
PAINT GREEN (-5875 5975);
DISPLAY INVISIBLE (-5875 5975);
FORCEPROP 1 LAST HDL_TAP TRUE
J 2
(-6200 5800);
DISPLAY 0.872340 (-6200 5800);
DISPLAY INVISIBLE (-6200 5800);
FORCEPROP 1 LAST PATH I245
J 2
(-5873 5925);
DISPLAY 0.872340 (-5873 5925);
PAINT GREEN (-5873 5925);
DISPLAY INVISIBLE (-5873 5925);
FORCEADD TAP..1
R 2
(-5875 5825);
FORCEPROP 3 LASTPIN (-5825 5825) SIG_NAME M_B_CPU1_SA_DQS_DP<2>
J 0
(-5815 5835);
DISPLAY 0.659574 (-5815 5835);
PAINT MONO (-5815 5835);
DISPLAY INVISIBLE (-5815 5835);
FORCEPROP 1 LASTPIN (-5825 5825) BN 2
J 2
(-5813 5833);
DISPLAY 0.489362 (-5813 5833);
PAINT GREEN (-5813 5833);
FORCEPROP 2 LAST CDS_LIB mstr_standard
J 2
(-5875 5825);
DISPLAY 0.723404 (-5875 5825);
PAINT MONO (-5875 5825);
DISPLAY INVISIBLE (-5875 5825);
FORCEPROP 1 LAST BODY_TYPE PLUMBING
J 2
(-5875 5875);
DISPLAY 0.872340 (-5875 5875);
PAINT GREEN (-5875 5875);
DISPLAY INVISIBLE (-5875 5875);
FORCEPROP 1 LAST HDL_TAP TRUE
J 2
(-6200 5700);
DISPLAY 0.872340 (-6200 5700);
DISPLAY INVISIBLE (-6200 5700);
FORCEPROP 1 LAST PATH I246
J 2
(-5873 5825);
DISPLAY 0.872340 (-5873 5825);
PAINT GREEN (-5873 5825);
DISPLAY INVISIBLE (-5873 5825);
FORCEADD TAP..1
R 2
(-5875 5725);
FORCEPROP 3 LASTPIN (-5825 5725) SIG_NAME M_B_CPU1_SA_DQS_DP<3>
J 0
(-5815 5735);
DISPLAY 0.659574 (-5815 5735);
PAINT MONO (-5815 5735);
DISPLAY INVISIBLE (-5815 5735);
FORCEPROP 1 LASTPIN (-5825 5725) BN 3
J 2
(-5813 5733);
DISPLAY 0.489362 (-5813 5733);
PAINT GREEN (-5813 5733);
FORCEPROP 2 LAST CDS_LIB mstr_standard
J 2
(-5875 5725);
DISPLAY 0.723404 (-5875 5725);
PAINT MONO (-5875 5725);
DISPLAY INVISIBLE (-5875 5725);
FORCEPROP 1 LAST BODY_TYPE PLUMBING
J 2
(-5875 5775);
DISPLAY 0.872340 (-5875 5775);
PAINT GREEN (-5875 5775);
DISPLAY INVISIBLE (-5875 5775);
FORCEPROP 1 LAST HDL_TAP TRUE
J 2
(-6200 5600);
DISPLAY 0.872340 (-6200 5600);
DISPLAY INVISIBLE (-6200 5600);
FORCEPROP 1 LAST PATH I247
J 2
(-5873 5725);
DISPLAY 0.872340 (-5873 5725);
PAINT GREEN (-5873 5725);
DISPLAY INVISIBLE (-5873 5725);
FORCEADD TAP..1
R 2
(-6075 5975);
FORCEPROP 3 LASTPIN (-6025 5975) SIG_NAME M_B_CPU1_SA_DQS_DN<0>
J 0
(-6015 5985);
DISPLAY 0.659574 (-6015 5985);
PAINT MONO (-6015 5985);
DISPLAY INVISIBLE (-6015 5985);
FORCEPROP 1 LASTPIN (-6025 5975) BN 0
J 2
(-6013 5983);
DISPLAY 0.489362 (-6013 5983);
PAINT GREEN (-6013 5983);
FORCEPROP 2 LAST CDS_LIB mstr_standard
J 2
(-6075 5975);
DISPLAY 0.723404 (-6075 5975);
PAINT MONO (-6075 5975);
DISPLAY INVISIBLE (-6075 5975);
FORCEPROP 1 LAST BODY_TYPE PLUMBING
J 2
(-6075 6025);
DISPLAY 0.872340 (-6075 6025);
PAINT GREEN (-6075 6025);
DISPLAY INVISIBLE (-6075 6025);
FORCEPROP 1 LAST HDL_TAP TRUE
J 2
(-6400 5850);
DISPLAY 0.872340 (-6400 5850);
DISPLAY INVISIBLE (-6400 5850);
FORCEPROP 1 LAST PATH I248
J 2
(-6073 5975);
DISPLAY 0.872340 (-6073 5975);
PAINT GREEN (-6073 5975);
DISPLAY INVISIBLE (-6073 5975);
FORCEADD TAP..1
R 2
(-6075 5875);
FORCEPROP 3 LASTPIN (-6025 5875) SIG_NAME M_B_CPU1_SA_DQS_DN<1>
J 0
(-6015 5885);
DISPLAY 0.659574 (-6015 5885);
PAINT MONO (-6015 5885);
DISPLAY INVISIBLE (-6015 5885);
FORCEPROP 1 LASTPIN (-6025 5875) BN 1
J 2
(-6013 5883);
DISPLAY 0.489362 (-6013 5883);
PAINT GREEN (-6013 5883);
FORCEPROP 2 LAST CDS_LIB mstr_standard
J 2
(-6075 5875);
DISPLAY 0.723404 (-6075 5875);
PAINT MONO (-6075 5875);
DISPLAY INVISIBLE (-6075 5875);
FORCEPROP 1 LAST BODY_TYPE PLUMBING
J 2
(-6075 5925);
DISPLAY 0.872340 (-6075 5925);
PAINT GREEN (-6075 5925);
DISPLAY INVISIBLE (-6075 5925);
FORCEPROP 1 LAST HDL_TAP TRUE
J 2
(-6400 5750);
DISPLAY 0.872340 (-6400 5750);
DISPLAY INVISIBLE (-6400 5750);
FORCEPROP 1 LAST PATH I249
J 2
(-6073 5875);
DISPLAY 0.872340 (-6073 5875);
PAINT GREEN (-6073 5875);
DISPLAY INVISIBLE (-6073 5875);
FORCEADD TAP..1
R 2
(-6075 5675);
FORCEPROP 3 LASTPIN (-6025 5675) SIG_NAME M_B_CPU1_SA_DQS_DN<3>
J 0
(-6015 5685);
DISPLAY 0.659574 (-6015 5685);
PAINT MONO (-6015 5685);
DISPLAY INVISIBLE (-6015 5685);
FORCEPROP 1 LASTPIN (-6025 5675) BN 3
J 2
(-6013 5683);
DISPLAY 0.489362 (-6013 5683);
PAINT GREEN (-6013 5683);
FORCEPROP 2 LAST CDS_LIB mstr_standard
J 2
(-6075 5675);
DISPLAY 0.723404 (-6075 5675);
PAINT MONO (-6075 5675);
DISPLAY INVISIBLE (-6075 5675);
FORCEPROP 1 LAST BODY_TYPE PLUMBING
J 2
(-6075 5725);
DISPLAY 0.872340 (-6075 5725);
PAINT GREEN (-6075 5725);
DISPLAY INVISIBLE (-6075 5725);
FORCEPROP 1 LAST HDL_TAP TRUE
J 2
(-6400 5550);
DISPLAY 0.872340 (-6400 5550);
DISPLAY INVISIBLE (-6400 5550);
FORCEPROP 1 LAST PATH I250
J 2
(-6073 5675);
DISPLAY 0.872340 (-6073 5675);
PAINT GREEN (-6073 5675);
DISPLAY INVISIBLE (-6073 5675);
FORCEADD TAP..1
R 2
(-6075 5775);
FORCEPROP 3 LASTPIN (-6025 5775) SIG_NAME M_B_CPU1_SA_DQS_DN<2>
J 0
(-6015 5785);
DISPLAY 0.659574 (-6015 5785);
PAINT MONO (-6015 5785);
DISPLAY INVISIBLE (-6015 5785);
FORCEPROP 1 LASTPIN (-6025 5775) BN 2
J 2
(-6013 5783);
DISPLAY 0.489362 (-6013 5783);
PAINT GREEN (-6013 5783);
FORCEPROP 2 LAST CDS_LIB mstr_standard
J 2
(-6075 5775);
DISPLAY 0.723404 (-6075 5775);
PAINT MONO (-6075 5775);
DISPLAY INVISIBLE (-6075 5775);
FORCEPROP 1 LAST BODY_TYPE PLUMBING
J 2
(-6075 5825);
DISPLAY 0.872340 (-6075 5825);
PAINT GREEN (-6075 5825);
DISPLAY INVISIBLE (-6075 5825);
FORCEPROP 1 LAST HDL_TAP TRUE
J 2
(-6400 5650);
DISPLAY 0.872340 (-6400 5650);
DISPLAY INVISIBLE (-6400 5650);
FORCEPROP 1 LAST PATH I251
J 2
(-6073 5775);
DISPLAY 0.872340 (-6073 5775);
PAINT GREEN (-6073 5775);
DISPLAY INVISIBLE (-6073 5775);
FORCEADD TAP..1
R 2
(-5875 5625);
FORCEPROP 3 LASTPIN (-5825 5625) SIG_NAME M_B_CPU1_SA_DQS_DP<4>
J 0
(-5815 5635);
DISPLAY 0.659574 (-5815 5635);
PAINT MONO (-5815 5635);
DISPLAY INVISIBLE (-5815 5635);
FORCEPROP 1 LASTPIN (-5825 5625) BN 4
J 2
(-5813 5633);
DISPLAY 0.489362 (-5813 5633);
PAINT GREEN (-5813 5633);
FORCEPROP 2 LAST CDS_LIB mstr_standard
J 2
(-5875 5625);
DISPLAY 0.723404 (-5875 5625);
PAINT MONO (-5875 5625);
DISPLAY INVISIBLE (-5875 5625);
FORCEPROP 1 LAST BODY_TYPE PLUMBING
J 2
(-5875 5675);
DISPLAY 0.872340 (-5875 5675);
PAINT GREEN (-5875 5675);
DISPLAY INVISIBLE (-5875 5675);
FORCEPROP 1 LAST HDL_TAP TRUE
J 2
(-6200 5500);
DISPLAY 0.872340 (-6200 5500);
DISPLAY INVISIBLE (-6200 5500);
FORCEPROP 1 LAST PATH I252
J 2
(-5873 5625);
DISPLAY 0.872340 (-5873 5625);
PAINT GREEN (-5873 5625);
DISPLAY INVISIBLE (-5873 5625);
FORCEADD TAP..1
R 2
(-5875 5525);
FORCEPROP 3 LASTPIN (-5825 5525) SIG_NAME M_B_CPU1_SA_DQS_DP<5>
J 0
(-5815 5535);
DISPLAY 0.659574 (-5815 5535);
PAINT MONO (-5815 5535);
DISPLAY INVISIBLE (-5815 5535);
FORCEPROP 1 LASTPIN (-5825 5525) BN 5
J 2
(-5813 5533);
DISPLAY 0.489362 (-5813 5533);
PAINT GREEN (-5813 5533);
FORCEPROP 2 LAST CDS_LIB mstr_standard
J 2
(-5875 5525);
DISPLAY 0.723404 (-5875 5525);
PAINT MONO (-5875 5525);
DISPLAY INVISIBLE (-5875 5525);
FORCEPROP 1 LAST BODY_TYPE PLUMBING
J 2
(-5875 5575);
DISPLAY 0.872340 (-5875 5575);
PAINT GREEN (-5875 5575);
DISPLAY INVISIBLE (-5875 5575);
FORCEPROP 1 LAST HDL_TAP TRUE
J 2
(-6200 5400);
DISPLAY 0.872340 (-6200 5400);
DISPLAY INVISIBLE (-6200 5400);
FORCEPROP 1 LAST PATH I253
J 2
(-5873 5525);
DISPLAY 0.872340 (-5873 5525);
PAINT GREEN (-5873 5525);
DISPLAY INVISIBLE (-5873 5525);
FORCEADD TAP..1
R 2
(-5875 5425);
FORCEPROP 3 LASTPIN (-5825 5425) SIG_NAME M_B_CPU1_SA_DQS_DP<6>
J 0
(-5815 5435);
DISPLAY 0.659574 (-5815 5435);
PAINT MONO (-5815 5435);
DISPLAY INVISIBLE (-5815 5435);
FORCEPROP 1 LASTPIN (-5825 5425) BN 6
J 2
(-5813 5433);
DISPLAY 0.489362 (-5813 5433);
PAINT GREEN (-5813 5433);
FORCEPROP 2 LAST CDS_LIB mstr_standard
J 2
(-5875 5425);
DISPLAY 0.723404 (-5875 5425);
PAINT MONO (-5875 5425);
DISPLAY INVISIBLE (-5875 5425);
FORCEPROP 1 LAST BODY_TYPE PLUMBING
J 2
(-5875 5475);
DISPLAY 0.872340 (-5875 5475);
PAINT GREEN (-5875 5475);
DISPLAY INVISIBLE (-5875 5475);
FORCEPROP 1 LAST HDL_TAP TRUE
J 2
(-6200 5300);
DISPLAY 0.872340 (-6200 5300);
DISPLAY INVISIBLE (-6200 5300);
FORCEPROP 1 LAST PATH I254
J 2
(-5873 5425);
DISPLAY 0.872340 (-5873 5425);
PAINT GREEN (-5873 5425);
DISPLAY INVISIBLE (-5873 5425);
FORCEADD TAP..1
R 2
(-5875 5325);
FORCEPROP 3 LASTPIN (-5825 5325) SIG_NAME M_B_CPU1_SA_DQS_DP<7>
J 0
(-5815 5335);
DISPLAY 0.659574 (-5815 5335);
PAINT MONO (-5815 5335);
DISPLAY INVISIBLE (-5815 5335);
FORCEPROP 1 LASTPIN (-5825 5325) BN 7
J 2
(-5813 5333);
DISPLAY 0.489362 (-5813 5333);
PAINT GREEN (-5813 5333);
FORCEPROP 2 LAST CDS_LIB mstr_standard
J 2
(-5875 5325);
DISPLAY 0.723404 (-5875 5325);
PAINT MONO (-5875 5325);
DISPLAY INVISIBLE (-5875 5325);
FORCEPROP 1 LAST BODY_TYPE PLUMBING
J 2
(-5875 5375);
DISPLAY 0.872340 (-5875 5375);
PAINT GREEN (-5875 5375);
DISPLAY INVISIBLE (-5875 5375);
FORCEPROP 1 LAST HDL_TAP TRUE
J 2
(-6200 5200);
DISPLAY 0.872340 (-6200 5200);
DISPLAY INVISIBLE (-6200 5200);
FORCEPROP 1 LAST PATH I255
J 2
(-5873 5325);
DISPLAY 0.872340 (-5873 5325);
PAINT GREEN (-5873 5325);
DISPLAY INVISIBLE (-5873 5325);
FORCEADD TAP..1
R 2
(-5875 5125);
FORCEPROP 3 LASTPIN (-5825 5125) SIG_NAME M_B_CPU1_SA_DQS_DP<9>
J 0
(-5815 5135);
DISPLAY 0.659574 (-5815 5135);
PAINT MONO (-5815 5135);
DISPLAY INVISIBLE (-5815 5135);
FORCEPROP 1 LASTPIN (-5825 5125) BN 9
J 2
(-5813 5133);
DISPLAY 0.489362 (-5813 5133);
PAINT GREEN (-5813 5133);
FORCEPROP 2 LAST CDS_LIB mstr_standard
J 2
(-5875 5125);
DISPLAY 0.723404 (-5875 5125);
PAINT MONO (-5875 5125);
DISPLAY INVISIBLE (-5875 5125);
FORCEPROP 1 LAST BODY_TYPE PLUMBING
J 2
(-5875 5175);
DISPLAY 0.872340 (-5875 5175);
PAINT GREEN (-5875 5175);
DISPLAY INVISIBLE (-5875 5175);
FORCEPROP 1 LAST HDL_TAP TRUE
J 2
(-6200 5000);
DISPLAY 0.872340 (-6200 5000);
DISPLAY INVISIBLE (-6200 5000);
FORCEPROP 1 LAST PATH I256
J 2
(-5873 5125);
DISPLAY 0.872340 (-5873 5125);
PAINT GREEN (-5873 5125);
DISPLAY INVISIBLE (-5873 5125);
FORCEADD TAP..1
R 2
(-5875 5225);
FORCEPROP 3 LASTPIN (-5825 5225) SIG_NAME M_B_CPU1_SA_DQS_DP<8>
J 0
(-5815 5235);
DISPLAY 0.659574 (-5815 5235);
PAINT MONO (-5815 5235);
DISPLAY INVISIBLE (-5815 5235);
FORCEPROP 1 LASTPIN (-5825 5225) BN 8
J 2
(-5813 5233);
DISPLAY 0.489362 (-5813 5233);
PAINT GREEN (-5813 5233);
FORCEPROP 2 LAST CDS_LIB mstr_standard
J 2
(-5875 5225);
DISPLAY 0.723404 (-5875 5225);
PAINT MONO (-5875 5225);
DISPLAY INVISIBLE (-5875 5225);
FORCEPROP 1 LAST BODY_TYPE PLUMBING
J 2
(-5875 5275);
DISPLAY 0.872340 (-5875 5275);
PAINT GREEN (-5875 5275);
DISPLAY INVISIBLE (-5875 5275);
FORCEPROP 1 LAST HDL_TAP TRUE
J 2
(-6200 5100);
DISPLAY 0.872340 (-6200 5100);
DISPLAY INVISIBLE (-6200 5100);
FORCEPROP 1 LAST PATH I257
J 2
(-5873 5225);
DISPLAY 0.872340 (-5873 5225);
PAINT GREEN (-5873 5225);
DISPLAY INVISIBLE (-5873 5225);
FORCEADD TAP..1
R 2
(-6075 5475);
FORCEPROP 3 LASTPIN (-6025 5475) SIG_NAME M_B_CPU1_SA_DQS_DN<5>
J 0
(-6015 5485);
DISPLAY 0.659574 (-6015 5485);
PAINT MONO (-6015 5485);
DISPLAY INVISIBLE (-6015 5485);
FORCEPROP 1 LASTPIN (-6025 5475) BN 5
J 2
(-6013 5483);
DISPLAY 0.489362 (-6013 5483);
PAINT GREEN (-6013 5483);
FORCEPROP 2 LAST CDS_LIB mstr_standard
J 2
(-6075 5475);
DISPLAY 0.723404 (-6075 5475);
PAINT MONO (-6075 5475);
DISPLAY INVISIBLE (-6075 5475);
FORCEPROP 1 LAST BODY_TYPE PLUMBING
J 2
(-6075 5525);
DISPLAY 0.872340 (-6075 5525);
PAINT GREEN (-6075 5525);
DISPLAY INVISIBLE (-6075 5525);
FORCEPROP 1 LAST HDL_TAP TRUE
J 2
(-6400 5350);
DISPLAY 0.872340 (-6400 5350);
DISPLAY INVISIBLE (-6400 5350);
FORCEPROP 1 LAST PATH I258
J 2
(-6073 5475);
DISPLAY 0.872340 (-6073 5475);
PAINT GREEN (-6073 5475);
DISPLAY INVISIBLE (-6073 5475);
FORCEADD TAP..1
R 2
(-6075 5575);
FORCEPROP 3 LASTPIN (-6025 5575) SIG_NAME M_B_CPU1_SA_DQS_DN<4>
J 0
(-6015 5585);
DISPLAY 0.659574 (-6015 5585);
PAINT MONO (-6015 5585);
DISPLAY INVISIBLE (-6015 5585);
FORCEPROP 1 LASTPIN (-6025 5575) BN 4
J 2
(-6013 5583);
DISPLAY 0.489362 (-6013 5583);
PAINT GREEN (-6013 5583);
FORCEPROP 2 LAST CDS_LIB mstr_standard
J 2
(-6075 5575);
DISPLAY 0.723404 (-6075 5575);
PAINT MONO (-6075 5575);
DISPLAY INVISIBLE (-6075 5575);
FORCEPROP 1 LAST BODY_TYPE PLUMBING
J 2
(-6075 5625);
DISPLAY 0.872340 (-6075 5625);
PAINT GREEN (-6075 5625);
DISPLAY INVISIBLE (-6075 5625);
FORCEPROP 1 LAST HDL_TAP TRUE
J 2
(-6400 5450);
DISPLAY 0.872340 (-6400 5450);
DISPLAY INVISIBLE (-6400 5450);
FORCEPROP 1 LAST PATH I259
J 2
(-6073 5575);
DISPLAY 0.872340 (-6073 5575);
PAINT GREEN (-6073 5575);
DISPLAY INVISIBLE (-6073 5575);
FORCEADD TAP..1
R 2
(-6075 5375);
FORCEPROP 3 LASTPIN (-6025 5375) SIG_NAME M_B_CPU1_SA_DQS_DN<6>
J 0
(-6015 5385);
DISPLAY 0.659574 (-6015 5385);
PAINT MONO (-6015 5385);
DISPLAY INVISIBLE (-6015 5385);
FORCEPROP 1 LASTPIN (-6025 5375) BN 6
J 2
(-6013 5383);
DISPLAY 0.489362 (-6013 5383);
PAINT GREEN (-6013 5383);
FORCEPROP 2 LAST CDS_LIB mstr_standard
J 2
(-6075 5375);
DISPLAY 0.723404 (-6075 5375);
PAINT MONO (-6075 5375);
DISPLAY INVISIBLE (-6075 5375);
FORCEPROP 1 LAST BODY_TYPE PLUMBING
J 2
(-6075 5425);
DISPLAY 0.872340 (-6075 5425);
PAINT GREEN (-6075 5425);
DISPLAY INVISIBLE (-6075 5425);
FORCEPROP 1 LAST HDL_TAP TRUE
J 2
(-6400 5250);
DISPLAY 0.872340 (-6400 5250);
DISPLAY INVISIBLE (-6400 5250);
FORCEPROP 1 LAST PATH I260
J 2
(-6073 5375);
DISPLAY 0.872340 (-6073 5375);
PAINT GREEN (-6073 5375);
DISPLAY INVISIBLE (-6073 5375);
FORCEADD TAP..1
R 2
(-6075 5275);
FORCEPROP 3 LASTPIN (-6025 5275) SIG_NAME M_B_CPU1_SA_DQS_DN<7>
J 0
(-6015 5285);
DISPLAY 0.659574 (-6015 5285);
PAINT MONO (-6015 5285);
DISPLAY INVISIBLE (-6015 5285);
FORCEPROP 1 LASTPIN (-6025 5275) BN 7
J 2
(-6013 5283);
DISPLAY 0.489362 (-6013 5283);
PAINT GREEN (-6013 5283);
FORCEPROP 2 LAST CDS_LIB mstr_standard
J 2
(-6075 5275);
DISPLAY 0.723404 (-6075 5275);
PAINT MONO (-6075 5275);
DISPLAY INVISIBLE (-6075 5275);
FORCEPROP 1 LAST BODY_TYPE PLUMBING
J 2
(-6075 5325);
DISPLAY 0.872340 (-6075 5325);
PAINT GREEN (-6075 5325);
DISPLAY INVISIBLE (-6075 5325);
FORCEPROP 1 LAST HDL_TAP TRUE
J 2
(-6400 5150);
DISPLAY 0.872340 (-6400 5150);
DISPLAY INVISIBLE (-6400 5150);
FORCEPROP 1 LAST PATH I261
J 2
(-6073 5275);
DISPLAY 0.872340 (-6073 5275);
PAINT GREEN (-6073 5275);
DISPLAY INVISIBLE (-6073 5275);
FORCEADD TAP..1
R 2
(-6075 5175);
FORCEPROP 3 LASTPIN (-6025 5175) SIG_NAME M_B_CPU1_SA_DQS_DN<8>
J 0
(-6015 5185);
DISPLAY 0.659574 (-6015 5185);
PAINT MONO (-6015 5185);
DISPLAY INVISIBLE (-6015 5185);
FORCEPROP 1 LASTPIN (-6025 5175) BN 8
J 2
(-6013 5183);
DISPLAY 0.489362 (-6013 5183);
PAINT GREEN (-6013 5183);
FORCEPROP 2 LAST CDS_LIB mstr_standard
J 2
(-6075 5175);
DISPLAY 0.723404 (-6075 5175);
PAINT MONO (-6075 5175);
DISPLAY INVISIBLE (-6075 5175);
FORCEPROP 1 LAST BODY_TYPE PLUMBING
J 2
(-6075 5225);
DISPLAY 0.872340 (-6075 5225);
PAINT GREEN (-6075 5225);
DISPLAY INVISIBLE (-6075 5225);
FORCEPROP 1 LAST HDL_TAP TRUE
J 2
(-6400 5050);
DISPLAY 0.872340 (-6400 5050);
DISPLAY INVISIBLE (-6400 5050);
FORCEPROP 1 LAST PATH I262
J 2
(-6073 5175);
DISPLAY 0.872340 (-6073 5175);
PAINT GREEN (-6073 5175);
DISPLAY INVISIBLE (-6073 5175);
FORCEADD TAP..1
R 2
(-5875 4975);
FORCEPROP 3 LASTPIN (-5825 4975) SIG_NAME M_B_CPU1_SB_DQS_DP<0>
J 0
(-5815 4985);
DISPLAY 0.659574 (-5815 4985);
PAINT MONO (-5815 4985);
DISPLAY INVISIBLE (-5815 4985);
FORCEPROP 1 LASTPIN (-5825 4975) BN 0
J 2
(-5813 4983);
DISPLAY 0.489362 (-5813 4983);
PAINT GREEN (-5813 4983);
FORCEPROP 2 LAST CDS_LIB mstr_standard
J 2
(-5875 4975);
DISPLAY 0.723404 (-5875 4975);
PAINT MONO (-5875 4975);
DISPLAY INVISIBLE (-5875 4975);
FORCEPROP 1 LAST BODY_TYPE PLUMBING
J 2
(-5875 5025);
DISPLAY 0.872340 (-5875 5025);
PAINT GREEN (-5875 5025);
DISPLAY INVISIBLE (-5875 5025);
FORCEPROP 1 LAST HDL_TAP TRUE
J 2
(-6200 4850);
DISPLAY 0.872340 (-6200 4850);
DISPLAY INVISIBLE (-6200 4850);
FORCEPROP 1 LAST PATH I263
J 2
(-5873 4975);
DISPLAY 0.872340 (-5873 4975);
PAINT GREEN (-5873 4975);
DISPLAY INVISIBLE (-5873 4975);
FORCEADD TAP..1
R 2
(-5875 4875);
FORCEPROP 3 LASTPIN (-5825 4875) SIG_NAME M_B_CPU1_SB_DQS_DP<1>
J 0
(-5815 4885);
DISPLAY 0.659574 (-5815 4885);
PAINT MONO (-5815 4885);
DISPLAY INVISIBLE (-5815 4885);
FORCEPROP 1 LASTPIN (-5825 4875) BN 1
J 2
(-5813 4883);
DISPLAY 0.489362 (-5813 4883);
PAINT GREEN (-5813 4883);
FORCEPROP 2 LAST CDS_LIB mstr_standard
J 2
(-5875 4875);
DISPLAY 0.723404 (-5875 4875);
PAINT MONO (-5875 4875);
DISPLAY INVISIBLE (-5875 4875);
FORCEPROP 1 LAST BODY_TYPE PLUMBING
J 2
(-5875 4925);
DISPLAY 0.872340 (-5875 4925);
PAINT GREEN (-5875 4925);
DISPLAY INVISIBLE (-5875 4925);
FORCEPROP 1 LAST HDL_TAP TRUE
J 2
(-6200 4750);
DISPLAY 0.872340 (-6200 4750);
DISPLAY INVISIBLE (-6200 4750);
FORCEPROP 1 LAST PATH I264
J 2
(-5873 4875);
DISPLAY 0.872340 (-5873 4875);
PAINT GREEN (-5873 4875);
DISPLAY INVISIBLE (-5873 4875);
FORCEADD TAP..1
R 2
(-5875 4775);
FORCEPROP 3 LASTPIN (-5825 4775) SIG_NAME M_B_CPU1_SB_DQS_DP<2>
J 0
(-5815 4785);
DISPLAY 0.659574 (-5815 4785);
PAINT MONO (-5815 4785);
DISPLAY INVISIBLE (-5815 4785);
FORCEPROP 1 LASTPIN (-5825 4775) BN 2
J 2
(-5813 4783);
DISPLAY 0.489362 (-5813 4783);
PAINT GREEN (-5813 4783);
FORCEPROP 2 LAST CDS_LIB mstr_standard
J 2
(-5875 4775);
DISPLAY 0.723404 (-5875 4775);
PAINT MONO (-5875 4775);
DISPLAY INVISIBLE (-5875 4775);
FORCEPROP 1 LAST BODY_TYPE PLUMBING
J 2
(-5875 4825);
DISPLAY 0.872340 (-5875 4825);
PAINT GREEN (-5875 4825);
DISPLAY INVISIBLE (-5875 4825);
FORCEPROP 1 LAST HDL_TAP TRUE
J 2
(-6200 4650);
DISPLAY 0.872340 (-6200 4650);
DISPLAY INVISIBLE (-6200 4650);
FORCEPROP 1 LAST PATH I265
J 2
(-5873 4775);
DISPLAY 0.872340 (-5873 4775);
PAINT GREEN (-5873 4775);
DISPLAY INVISIBLE (-5873 4775);
FORCEADD TAP..1
R 2
(-5875 4675);
FORCEPROP 3 LASTPIN (-5825 4675) SIG_NAME M_B_CPU1_SB_DQS_DP<3>
J 0
(-5815 4685);
DISPLAY 0.659574 (-5815 4685);
PAINT MONO (-5815 4685);
DISPLAY INVISIBLE (-5815 4685);
FORCEPROP 1 LASTPIN (-5825 4675) BN 3
J 2
(-5813 4683);
DISPLAY 0.489362 (-5813 4683);
PAINT GREEN (-5813 4683);
FORCEPROP 2 LAST CDS_LIB mstr_standard
J 2
(-5875 4675);
DISPLAY 0.723404 (-5875 4675);
PAINT MONO (-5875 4675);
DISPLAY INVISIBLE (-5875 4675);
FORCEPROP 1 LAST BODY_TYPE PLUMBING
J 2
(-5875 4725);
DISPLAY 0.872340 (-5875 4725);
PAINT GREEN (-5875 4725);
DISPLAY INVISIBLE (-5875 4725);
FORCEPROP 1 LAST HDL_TAP TRUE
J 2
(-6200 4550);
DISPLAY 0.872340 (-6200 4550);
DISPLAY INVISIBLE (-6200 4550);
FORCEPROP 1 LAST PATH I266
J 2
(-5873 4675);
DISPLAY 0.872340 (-5873 4675);
PAINT GREEN (-5873 4675);
DISPLAY INVISIBLE (-5873 4675);
FORCEADD TAP..1
R 2
(-6075 4925);
FORCEPROP 3 LASTPIN (-6025 4925) SIG_NAME M_B_CPU1_SB_DQS_DN<0>
J 0
(-6015 4935);
DISPLAY 0.659574 (-6015 4935);
PAINT MONO (-6015 4935);
DISPLAY INVISIBLE (-6015 4935);
FORCEPROP 1 LASTPIN (-6025 4925) BN 0
J 2
(-6013 4933);
DISPLAY 0.489362 (-6013 4933);
PAINT GREEN (-6013 4933);
FORCEPROP 2 LAST CDS_LIB mstr_standard
J 2
(-6075 4925);
DISPLAY 0.723404 (-6075 4925);
PAINT MONO (-6075 4925);
DISPLAY INVISIBLE (-6075 4925);
FORCEPROP 1 LAST BODY_TYPE PLUMBING
J 2
(-6075 4975);
DISPLAY 0.872340 (-6075 4975);
PAINT GREEN (-6075 4975);
DISPLAY INVISIBLE (-6075 4975);
FORCEPROP 1 LAST HDL_TAP TRUE
J 2
(-6400 4800);
DISPLAY 0.872340 (-6400 4800);
DISPLAY INVISIBLE (-6400 4800);
FORCEPROP 1 LAST PATH I267
J 2
(-6073 4925);
DISPLAY 0.872340 (-6073 4925);
PAINT GREEN (-6073 4925);
DISPLAY INVISIBLE (-6073 4925);
FORCEADD TAP..1
R 2
(-6075 5075);
FORCEPROP 3 LASTPIN (-6025 5075) SIG_NAME M_B_CPU1_SA_DQS_DN<9>
J 0
(-6015 5085);
DISPLAY 0.659574 (-6015 5085);
PAINT MONO (-6015 5085);
DISPLAY INVISIBLE (-6015 5085);
FORCEPROP 1 LASTPIN (-6025 5075) BN 9
J 2
(-6013 5083);
DISPLAY 0.489362 (-6013 5083);
PAINT GREEN (-6013 5083);
FORCEPROP 2 LAST CDS_LIB mstr_standard
J 2
(-6075 5075);
DISPLAY 0.723404 (-6075 5075);
PAINT MONO (-6075 5075);
DISPLAY INVISIBLE (-6075 5075);
FORCEPROP 1 LAST BODY_TYPE PLUMBING
J 2
(-6075 5125);
DISPLAY 0.872340 (-6075 5125);
PAINT GREEN (-6075 5125);
DISPLAY INVISIBLE (-6075 5125);
FORCEPROP 1 LAST HDL_TAP TRUE
J 2
(-6400 4950);
DISPLAY 0.872340 (-6400 4950);
DISPLAY INVISIBLE (-6400 4950);
FORCEPROP 1 LAST PATH I268
J 2
(-6073 5075);
DISPLAY 0.872340 (-6073 5075);
PAINT GREEN (-6073 5075);
DISPLAY INVISIBLE (-6073 5075);
FORCEADD TAP..1
R 2
(-6075 4825);
FORCEPROP 3 LASTPIN (-6025 4825) SIG_NAME M_B_CPU1_SB_DQS_DN<1>
J 0
(-6015 4835);
DISPLAY 0.659574 (-6015 4835);
PAINT MONO (-6015 4835);
DISPLAY INVISIBLE (-6015 4835);
FORCEPROP 1 LASTPIN (-6025 4825) BN 1
J 2
(-6013 4833);
DISPLAY 0.489362 (-6013 4833);
PAINT GREEN (-6013 4833);
FORCEPROP 2 LAST CDS_LIB mstr_standard
J 2
(-6075 4825);
DISPLAY 0.723404 (-6075 4825);
PAINT MONO (-6075 4825);
DISPLAY INVISIBLE (-6075 4825);
FORCEPROP 1 LAST BODY_TYPE PLUMBING
J 2
(-6075 4875);
DISPLAY 0.872340 (-6075 4875);
PAINT GREEN (-6075 4875);
DISPLAY INVISIBLE (-6075 4875);
FORCEPROP 1 LAST HDL_TAP TRUE
J 2
(-6400 4700);
DISPLAY 0.872340 (-6400 4700);
DISPLAY INVISIBLE (-6400 4700);
FORCEPROP 1 LAST PATH I269
J 2
(-6073 4825);
DISPLAY 0.872340 (-6073 4825);
PAINT GREEN (-6073 4825);
DISPLAY INVISIBLE (-6073 4825);
FORCEADD TAP..1
R 2
(-6075 4725);
FORCEPROP 3 LASTPIN (-6025 4725) SIG_NAME M_B_CPU1_SB_DQS_DN<2>
J 0
(-6015 4735);
DISPLAY 0.659574 (-6015 4735);
PAINT MONO (-6015 4735);
DISPLAY INVISIBLE (-6015 4735);
FORCEPROP 1 LASTPIN (-6025 4725) BN 2
J 2
(-6013 4733);
DISPLAY 0.489362 (-6013 4733);
PAINT GREEN (-6013 4733);
FORCEPROP 2 LAST CDS_LIB mstr_standard
J 2
(-6075 4725);
DISPLAY 0.723404 (-6075 4725);
PAINT MONO (-6075 4725);
DISPLAY INVISIBLE (-6075 4725);
FORCEPROP 1 LAST BODY_TYPE PLUMBING
J 2
(-6075 4775);
DISPLAY 0.872340 (-6075 4775);
PAINT GREEN (-6075 4775);
DISPLAY INVISIBLE (-6075 4775);
FORCEPROP 1 LAST HDL_TAP TRUE
J 2
(-6400 4600);
DISPLAY 0.872340 (-6400 4600);
DISPLAY INVISIBLE (-6400 4600);
FORCEPROP 1 LAST PATH I270
J 2
(-6073 4725);
DISPLAY 0.872340 (-6073 4725);
PAINT GREEN (-6073 4725);
DISPLAY INVISIBLE (-6073 4725);
FORCEADD TAP..1
R 2
(-6075 4625);
FORCEPROP 3 LASTPIN (-6025 4625) SIG_NAME M_B_CPU1_SB_DQS_DN<3>
J 0
(-6015 4635);
DISPLAY 0.659574 (-6015 4635);
PAINT MONO (-6015 4635);
DISPLAY INVISIBLE (-6015 4635);
FORCEPROP 1 LASTPIN (-6025 4625) BN 3
J 2
(-6013 4633);
DISPLAY 0.489362 (-6013 4633);
PAINT GREEN (-6013 4633);
FORCEPROP 2 LAST CDS_LIB mstr_standard
J 2
(-6075 4625);
DISPLAY 0.723404 (-6075 4625);
PAINT MONO (-6075 4625);
DISPLAY INVISIBLE (-6075 4625);
FORCEPROP 1 LAST BODY_TYPE PLUMBING
J 2
(-6075 4675);
DISPLAY 0.872340 (-6075 4675);
PAINT GREEN (-6075 4675);
DISPLAY INVISIBLE (-6075 4675);
FORCEPROP 1 LAST HDL_TAP TRUE
J 2
(-6400 4500);
DISPLAY 0.872340 (-6400 4500);
DISPLAY INVISIBLE (-6400 4500);
FORCEPROP 1 LAST PATH I271
J 2
(-6073 4625);
DISPLAY 0.872340 (-6073 4625);
PAINT GREEN (-6073 4625);
DISPLAY INVISIBLE (-6073 4625);
FORCEADD TAP..1
R 2
(-5875 4575);
FORCEPROP 3 LASTPIN (-5825 4575) SIG_NAME M_B_CPU1_SB_DQS_DP<4>
J 0
(-5815 4585);
DISPLAY 0.659574 (-5815 4585);
PAINT MONO (-5815 4585);
DISPLAY INVISIBLE (-5815 4585);
FORCEPROP 1 LASTPIN (-5825 4575) BN 4
J 2
(-5813 4583);
DISPLAY 0.489362 (-5813 4583);
PAINT GREEN (-5813 4583);
FORCEPROP 2 LAST CDS_LIB mstr_standard
J 2
(-5875 4575);
DISPLAY 0.723404 (-5875 4575);
PAINT MONO (-5875 4575);
DISPLAY INVISIBLE (-5875 4575);
FORCEPROP 1 LAST BODY_TYPE PLUMBING
J 2
(-5875 4625);
DISPLAY 0.872340 (-5875 4625);
PAINT GREEN (-5875 4625);
DISPLAY INVISIBLE (-5875 4625);
FORCEPROP 1 LAST HDL_TAP TRUE
J 2
(-6200 4450);
DISPLAY 0.872340 (-6200 4450);
DISPLAY INVISIBLE (-6200 4450);
FORCEPROP 1 LAST PATH I272
J 2
(-5873 4575);
DISPLAY 0.872340 (-5873 4575);
PAINT GREEN (-5873 4575);
DISPLAY INVISIBLE (-5873 4575);
FORCEADD TAP..1
R 2
(-5875 4375);
FORCEPROP 3 LASTPIN (-5825 4375) SIG_NAME M_B_CPU1_SB_DQS_DP<6>
J 0
(-5815 4385);
DISPLAY 0.659574 (-5815 4385);
PAINT MONO (-5815 4385);
DISPLAY INVISIBLE (-5815 4385);
FORCEPROP 1 LASTPIN (-5825 4375) BN 6
J 2
(-5813 4383);
DISPLAY 0.489362 (-5813 4383);
PAINT GREEN (-5813 4383);
FORCEPROP 2 LAST CDS_LIB mstr_standard
J 2
(-5875 4375);
DISPLAY 0.723404 (-5875 4375);
PAINT MONO (-5875 4375);
DISPLAY INVISIBLE (-5875 4375);
FORCEPROP 1 LAST BODY_TYPE PLUMBING
J 2
(-5875 4425);
DISPLAY 0.872340 (-5875 4425);
PAINT GREEN (-5875 4425);
DISPLAY INVISIBLE (-5875 4425);
FORCEPROP 1 LAST HDL_TAP TRUE
J 2
(-6200 4250);
DISPLAY 0.872340 (-6200 4250);
DISPLAY INVISIBLE (-6200 4250);
FORCEPROP 1 LAST PATH I273
J 2
(-5873 4375);
DISPLAY 0.872340 (-5873 4375);
PAINT GREEN (-5873 4375);
DISPLAY INVISIBLE (-5873 4375);
FORCEADD TAP..1
R 2
(-5875 4475);
FORCEPROP 3 LASTPIN (-5825 4475) SIG_NAME M_B_CPU1_SB_DQS_DP<5>
J 0
(-5815 4485);
DISPLAY 0.659574 (-5815 4485);
PAINT MONO (-5815 4485);
DISPLAY INVISIBLE (-5815 4485);
FORCEPROP 1 LASTPIN (-5825 4475) BN 5
J 2
(-5813 4483);
DISPLAY 0.489362 (-5813 4483);
PAINT GREEN (-5813 4483);
FORCEPROP 2 LAST CDS_LIB mstr_standard
J 2
(-5875 4475);
DISPLAY 0.723404 (-5875 4475);
PAINT MONO (-5875 4475);
DISPLAY INVISIBLE (-5875 4475);
FORCEPROP 1 LAST BODY_TYPE PLUMBING
J 2
(-5875 4525);
DISPLAY 0.872340 (-5875 4525);
PAINT GREEN (-5875 4525);
DISPLAY INVISIBLE (-5875 4525);
FORCEPROP 1 LAST HDL_TAP TRUE
J 2
(-6200 4350);
DISPLAY 0.872340 (-6200 4350);
DISPLAY INVISIBLE (-6200 4350);
FORCEPROP 1 LAST PATH I274
J 2
(-5873 4475);
DISPLAY 0.872340 (-5873 4475);
PAINT GREEN (-5873 4475);
DISPLAY INVISIBLE (-5873 4475);
FORCEADD TAP..1
R 2
(-5875 4275);
FORCEPROP 3 LASTPIN (-5825 4275) SIG_NAME M_B_CPU1_SB_DQS_DP<7>
J 0
(-5815 4285);
DISPLAY 0.659574 (-5815 4285);
PAINT MONO (-5815 4285);
DISPLAY INVISIBLE (-5815 4285);
FORCEPROP 1 LASTPIN (-5825 4275) BN 7
J 2
(-5813 4283);
DISPLAY 0.489362 (-5813 4283);
PAINT GREEN (-5813 4283);
FORCEPROP 2 LAST CDS_LIB mstr_standard
J 2
(-5875 4275);
DISPLAY 0.723404 (-5875 4275);
PAINT MONO (-5875 4275);
DISPLAY INVISIBLE (-5875 4275);
FORCEPROP 1 LAST BODY_TYPE PLUMBING
J 2
(-5875 4325);
DISPLAY 0.872340 (-5875 4325);
PAINT GREEN (-5875 4325);
DISPLAY INVISIBLE (-5875 4325);
FORCEPROP 1 LAST HDL_TAP TRUE
J 2
(-6200 4150);
DISPLAY 0.872340 (-6200 4150);
DISPLAY INVISIBLE (-6200 4150);
FORCEPROP 1 LAST PATH I275
J 2
(-5873 4275);
DISPLAY 0.872340 (-5873 4275);
PAINT GREEN (-5873 4275);
DISPLAY INVISIBLE (-5873 4275);
FORCEADD TAP..1
R 2
(-5875 4175);
FORCEPROP 3 LASTPIN (-5825 4175) SIG_NAME M_B_CPU1_SB_DQS_DP<8>
J 0
(-5815 4185);
DISPLAY 0.659574 (-5815 4185);
PAINT MONO (-5815 4185);
DISPLAY INVISIBLE (-5815 4185);
FORCEPROP 1 LASTPIN (-5825 4175) BN 8
J 2
(-5813 4183);
DISPLAY 0.489362 (-5813 4183);
PAINT GREEN (-5813 4183);
FORCEPROP 2 LAST CDS_LIB mstr_standard
J 2
(-5875 4175);
DISPLAY 0.723404 (-5875 4175);
PAINT MONO (-5875 4175);
DISPLAY INVISIBLE (-5875 4175);
FORCEPROP 1 LAST BODY_TYPE PLUMBING
J 2
(-5875 4225);
DISPLAY 0.872340 (-5875 4225);
PAINT GREEN (-5875 4225);
DISPLAY INVISIBLE (-5875 4225);
FORCEPROP 1 LAST HDL_TAP TRUE
J 2
(-6200 4050);
DISPLAY 0.872340 (-6200 4050);
DISPLAY INVISIBLE (-6200 4050);
FORCEPROP 1 LAST PATH I276
J 2
(-5873 4175);
DISPLAY 0.872340 (-5873 4175);
PAINT GREEN (-5873 4175);
DISPLAY INVISIBLE (-5873 4175);
FORCEADD TAP..1
R 2
(-6075 4425);
FORCEPROP 3 LASTPIN (-6025 4425) SIG_NAME M_B_CPU1_SB_DQS_DN<5>
J 0
(-6015 4435);
DISPLAY 0.659574 (-6015 4435);
PAINT MONO (-6015 4435);
DISPLAY INVISIBLE (-6015 4435);
FORCEPROP 1 LASTPIN (-6025 4425) BN 5
J 2
(-6013 4433);
DISPLAY 0.489362 (-6013 4433);
PAINT GREEN (-6013 4433);
FORCEPROP 2 LAST CDS_LIB mstr_standard
J 2
(-6075 4425);
DISPLAY 0.723404 (-6075 4425);
PAINT MONO (-6075 4425);
DISPLAY INVISIBLE (-6075 4425);
FORCEPROP 1 LAST BODY_TYPE PLUMBING
J 2
(-6075 4475);
DISPLAY 0.872340 (-6075 4475);
PAINT GREEN (-6075 4475);
DISPLAY INVISIBLE (-6075 4475);
FORCEPROP 1 LAST HDL_TAP TRUE
J 2
(-6400 4300);
DISPLAY 0.872340 (-6400 4300);
DISPLAY INVISIBLE (-6400 4300);
FORCEPROP 1 LAST PATH I277
J 2
(-6073 4425);
DISPLAY 0.872340 (-6073 4425);
PAINT GREEN (-6073 4425);
DISPLAY INVISIBLE (-6073 4425);
FORCEADD TAP..1
R 2
(-6075 4525);
FORCEPROP 3 LASTPIN (-6025 4525) SIG_NAME M_B_CPU1_SB_DQS_DN<4>
J 0
(-6015 4535);
DISPLAY 0.659574 (-6015 4535);
PAINT MONO (-6015 4535);
DISPLAY INVISIBLE (-6015 4535);
FORCEPROP 1 LASTPIN (-6025 4525) BN 4
J 2
(-6013 4533);
DISPLAY 0.489362 (-6013 4533);
PAINT GREEN (-6013 4533);
FORCEPROP 2 LAST CDS_LIB mstr_standard
J 2
(-6075 4525);
DISPLAY 0.723404 (-6075 4525);
PAINT MONO (-6075 4525);
DISPLAY INVISIBLE (-6075 4525);
FORCEPROP 1 LAST BODY_TYPE PLUMBING
J 2
(-6075 4575);
DISPLAY 0.872340 (-6075 4575);
PAINT GREEN (-6075 4575);
DISPLAY INVISIBLE (-6075 4575);
FORCEPROP 1 LAST HDL_TAP TRUE
J 2
(-6400 4400);
DISPLAY 0.872340 (-6400 4400);
DISPLAY INVISIBLE (-6400 4400);
FORCEPROP 1 LAST PATH I278
J 2
(-6073 4525);
DISPLAY 0.872340 (-6073 4525);
PAINT GREEN (-6073 4525);
DISPLAY INVISIBLE (-6073 4525);
FORCEADD TAP..1
R 2
(-6075 4325);
FORCEPROP 3 LASTPIN (-6025 4325) SIG_NAME M_B_CPU1_SB_DQS_DN<6>
J 0
(-6015 4335);
DISPLAY 0.659574 (-6015 4335);
PAINT MONO (-6015 4335);
DISPLAY INVISIBLE (-6015 4335);
FORCEPROP 1 LASTPIN (-6025 4325) BN 6
J 2
(-6013 4333);
DISPLAY 0.489362 (-6013 4333);
PAINT GREEN (-6013 4333);
FORCEPROP 2 LAST CDS_LIB mstr_standard
J 2
(-6075 4325);
DISPLAY 0.723404 (-6075 4325);
PAINT MONO (-6075 4325);
DISPLAY INVISIBLE (-6075 4325);
FORCEPROP 1 LAST BODY_TYPE PLUMBING
J 2
(-6075 4375);
DISPLAY 0.872340 (-6075 4375);
PAINT GREEN (-6075 4375);
DISPLAY INVISIBLE (-6075 4375);
FORCEPROP 1 LAST HDL_TAP TRUE
J 2
(-6400 4200);
DISPLAY 0.872340 (-6400 4200);
DISPLAY INVISIBLE (-6400 4200);
FORCEPROP 1 LAST PATH I279
J 2
(-6073 4325);
DISPLAY 0.872340 (-6073 4325);
PAINT GREEN (-6073 4325);
DISPLAY INVISIBLE (-6073 4325);
FORCEADD TAP..1
R 2
(-6075 4225);
FORCEPROP 3 LASTPIN (-6025 4225) SIG_NAME M_B_CPU1_SB_DQS_DN<7>
J 0
(-6015 4235);
DISPLAY 0.659574 (-6015 4235);
PAINT MONO (-6015 4235);
DISPLAY INVISIBLE (-6015 4235);
FORCEPROP 1 LASTPIN (-6025 4225) BN 7
J 2
(-6013 4233);
DISPLAY 0.489362 (-6013 4233);
PAINT GREEN (-6013 4233);
FORCEPROP 2 LAST CDS_LIB mstr_standard
J 2
(-6075 4225);
DISPLAY 0.723404 (-6075 4225);
PAINT MONO (-6075 4225);
DISPLAY INVISIBLE (-6075 4225);
FORCEPROP 1 LAST BODY_TYPE PLUMBING
J 2
(-6075 4275);
DISPLAY 0.872340 (-6075 4275);
PAINT GREEN (-6075 4275);
DISPLAY INVISIBLE (-6075 4275);
FORCEPROP 1 LAST HDL_TAP TRUE
J 2
(-6400 4100);
DISPLAY 0.872340 (-6400 4100);
DISPLAY INVISIBLE (-6400 4100);
FORCEPROP 1 LAST PATH I280
J 2
(-6073 4225);
DISPLAY 0.872340 (-6073 4225);
PAINT GREEN (-6073 4225);
DISPLAY INVISIBLE (-6073 4225);
FORCEADD TAP..1
R 2
(-6075 4125);
FORCEPROP 3 LASTPIN (-6025 4125) SIG_NAME M_B_CPU1_SB_DQS_DN<8>
J 0
(-6015 4135);
DISPLAY 0.659574 (-6015 4135);
PAINT MONO (-6015 4135);
DISPLAY INVISIBLE (-6015 4135);
FORCEPROP 1 LASTPIN (-6025 4125) BN 8
J 2
(-6013 4133);
DISPLAY 0.489362 (-6013 4133);
PAINT GREEN (-6013 4133);
FORCEPROP 2 LAST CDS_LIB mstr_standard
J 2
(-6075 4125);
DISPLAY 0.723404 (-6075 4125);
PAINT MONO (-6075 4125);
DISPLAY INVISIBLE (-6075 4125);
FORCEPROP 1 LAST BODY_TYPE PLUMBING
J 2
(-6075 4175);
DISPLAY 0.872340 (-6075 4175);
PAINT GREEN (-6075 4175);
DISPLAY INVISIBLE (-6075 4175);
FORCEPROP 1 LAST HDL_TAP TRUE
J 2
(-6400 4000);
DISPLAY 0.872340 (-6400 4000);
DISPLAY INVISIBLE (-6400 4000);
FORCEPROP 1 LAST PATH I281
J 2
(-6073 4125);
DISPLAY 0.872340 (-6073 4125);
PAINT GREEN (-6073 4125);
DISPLAY INVISIBLE (-6073 4125);
FORCEADD OFFPAGE..3
R 2
(-6775 6050);
FORCEPROP 2 LAST $XR0 98 
J 0
(-7054 6050);
DISPLAY 0.638298 (-7054 6050);
PAINT MONO (-7054 6050);
FORCEPROP 2 LAST PATH I282
J 0
(-7075 6100);
DISPLAY 1.021277 (-7075 6100);
DISPLAY INVISIBLE (-7075 6100);
FORCEPROP 1 LAST COMMENT_BODY TRUE
J 2
(-6725 5950);
DISPLAY 0.872340 (-6725 5950);
PAINT GREEN (-6725 5950);
DISPLAY INVISIBLE (-6725 5950);
FORCEPROP 1 LAST OFFPAGE TRUE
J 2
(-7100 5925);
DISPLAY 0.872340 (-7100 5925);
PAINT GREEN (-7100 5925);
DISPLAY INVISIBLE (-7100 5925);
FORCEPROP 2 LAST CDS_LIB standard
J 0
(-6775 6050);
DISPLAY INVISIBLE (-6775 6050);
FORCEADD OFFPAGE..3
R 2
(-6775 6000);
FORCEPROP 2 LAST $XR0 98 
J 0
(-7054 6000);
DISPLAY 0.638298 (-7054 6000);
PAINT MONO (-7054 6000);
FORCEPROP 2 LAST PATH I283
J 0
(-7075 6050);
DISPLAY 1.021277 (-7075 6050);
DISPLAY INVISIBLE (-7075 6050);
FORCEPROP 1 LAST COMMENT_BODY TRUE
J 2
(-6725 5900);
DISPLAY 0.872340 (-6725 5900);
PAINT GREEN (-6725 5900);
DISPLAY INVISIBLE (-6725 5900);
FORCEPROP 1 LAST OFFPAGE TRUE
J 2
(-7100 5875);
DISPLAY 0.872340 (-7100 5875);
PAINT GREEN (-7100 5875);
DISPLAY INVISIBLE (-7100 5875);
FORCEPROP 2 LAST CDS_LIB standard
J 0
(-6775 6000);
DISPLAY INVISIBLE (-6775 6000);
FORCEADD OFFPAGE..3
R 2
(-6775 4950);
FORCEPROP 2 LAST $XR0 98 
J 0
(-7054 4950);
DISPLAY 0.638298 (-7054 4950);
PAINT MONO (-7054 4950);
FORCEPROP 2 LAST PATH I284
J 0
(-7075 5000);
DISPLAY 1.021277 (-7075 5000);
DISPLAY INVISIBLE (-7075 5000);
FORCEPROP 1 LAST COMMENT_BODY TRUE
J 2
(-6725 4850);
DISPLAY 0.872340 (-6725 4850);
PAINT GREEN (-6725 4850);
DISPLAY INVISIBLE (-6725 4850);
FORCEPROP 1 LAST OFFPAGE TRUE
J 2
(-7100 4825);
DISPLAY 0.872340 (-7100 4825);
PAINT GREEN (-7100 4825);
DISPLAY INVISIBLE (-7100 4825);
FORCEPROP 2 LAST CDS_LIB standard
J 0
(-6775 4950);
DISPLAY INVISIBLE (-6775 4950);
FORCEADD OFFPAGE..3
R 2
(-6775 5000);
FORCEPROP 2 LAST $XR0 98 
J 0
(-7054 5000);
DISPLAY 0.638298 (-7054 5000);
PAINT MONO (-7054 5000);
FORCEPROP 2 LAST PATH I285
J 0
(-7075 5050);
DISPLAY 1.021277 (-7075 5050);
DISPLAY INVISIBLE (-7075 5050);
FORCEPROP 1 LAST COMMENT_BODY TRUE
J 2
(-6725 4900);
DISPLAY 0.872340 (-6725 4900);
PAINT GREEN (-6725 4900);
DISPLAY INVISIBLE (-6725 4900);
FORCEPROP 1 LAST OFFPAGE TRUE
J 2
(-7100 4875);
DISPLAY 0.872340 (-7100 4875);
PAINT GREEN (-7100 4875);
DISPLAY INVISIBLE (-7100 4875);
FORCEPROP 2 LAST CDS_LIB standard
J 0
(-6775 5000);
DISPLAY INVISIBLE (-6775 5000);
FORCEADD TAP..1
R 2
(-5875 4075);
FORCEPROP 3 LASTPIN (-5825 4075) SIG_NAME M_B_CPU1_SB_DQS_DP<9>
J 0
(-5815 4085);
DISPLAY 0.659574 (-5815 4085);
PAINT MONO (-5815 4085);
DISPLAY INVISIBLE (-5815 4085);
FORCEPROP 1 LASTPIN (-5825 4075) BN 9
J 2
(-5813 4083);
DISPLAY 0.489362 (-5813 4083);
PAINT GREEN (-5813 4083);
FORCEPROP 2 LAST CDS_LIB mstr_standard
J 2
(-5875 4075);
DISPLAY 0.723404 (-5875 4075);
PAINT MONO (-5875 4075);
DISPLAY INVISIBLE (-5875 4075);
FORCEPROP 1 LAST BODY_TYPE PLUMBING
J 2
(-5875 4125);
DISPLAY 0.872340 (-5875 4125);
PAINT GREEN (-5875 4125);
DISPLAY INVISIBLE (-5875 4125);
FORCEPROP 1 LAST HDL_TAP TRUE
J 2
(-6200 3950);
DISPLAY 0.872340 (-6200 3950);
DISPLAY INVISIBLE (-6200 3950);
FORCEPROP 1 LAST PATH I286
J 2
(-5873 4075);
DISPLAY 0.872340 (-5873 4075);
PAINT GREEN (-5873 4075);
DISPLAY INVISIBLE (-5873 4075);
FORCEADD TAP..1
R 2
(-6075 3875);
FORCEPROP 3 LASTPIN (-6025 3875) SIG_NAME M_B_CPU1_SA_CA<0>
J 0
(-6015 3885);
DISPLAY 0.659574 (-6015 3885);
PAINT MONO (-6015 3885);
DISPLAY INVISIBLE (-6015 3885);
FORCEPROP 1 LASTPIN (-6025 3875) BN 0
J 2
(-6013 3883);
DISPLAY 0.489362 (-6013 3883);
PAINT GREEN (-6013 3883);
FORCEPROP 2 LAST CDS_LIB mstr_standard
J 0
(-6075 3875);
DISPLAY 0.723404 (-6075 3875);
PAINT MONO (-6075 3875);
DISPLAY INVISIBLE (-6075 3875);
FORCEPROP 1 LAST BODY_TYPE PLUMBING
J 2
(-6075 3925);
DISPLAY 0.872340 (-6075 3925);
PAINT GREEN (-6075 3925);
DISPLAY INVISIBLE (-6075 3925);
FORCEPROP 1 LAST HDL_TAP TRUE
J 2
(-6400 3750);
DISPLAY 0.872340 (-6400 3750);
DISPLAY INVISIBLE (-6400 3750);
FORCEPROP 1 LAST PATH I287
J 2
(-6073 3875);
DISPLAY 0.872340 (-6073 3875);
PAINT GREEN (-6073 3875);
DISPLAY INVISIBLE (-6073 3875);
FORCEADD TAP..1
R 2
(-6075 4025);
FORCEPROP 3 LASTPIN (-6025 4025) SIG_NAME M_B_CPU1_SB_DQS_DN<9>
J 0
(-6015 4035);
DISPLAY 0.659574 (-6015 4035);
PAINT MONO (-6015 4035);
DISPLAY INVISIBLE (-6015 4035);
FORCEPROP 1 LASTPIN (-6025 4025) BN 9
J 2
(-6013 4033);
DISPLAY 0.489362 (-6013 4033);
PAINT GREEN (-6013 4033);
FORCEPROP 2 LAST CDS_LIB mstr_standard
J 2
(-6075 4025);
DISPLAY 0.723404 (-6075 4025);
PAINT MONO (-6075 4025);
DISPLAY INVISIBLE (-6075 4025);
FORCEPROP 1 LAST BODY_TYPE PLUMBING
J 2
(-6075 4075);
DISPLAY 0.872340 (-6075 4075);
PAINT GREEN (-6075 4075);
DISPLAY INVISIBLE (-6075 4075);
FORCEPROP 1 LAST HDL_TAP TRUE
J 2
(-6400 3900);
DISPLAY 0.872340 (-6400 3900);
DISPLAY INVISIBLE (-6400 3900);
FORCEPROP 1 LAST PATH I288
J 2
(-6073 4025);
DISPLAY 0.872340 (-6073 4025);
PAINT GREEN (-6073 4025);
DISPLAY INVISIBLE (-6073 4025);
FORCEADD TAP..1
R 2
(-6075 3825);
FORCEPROP 3 LASTPIN (-6025 3825) SIG_NAME M_B_CPU1_SA_CA<1>
J 0
(-6015 3835);
DISPLAY 0.659574 (-6015 3835);
PAINT MONO (-6015 3835);
DISPLAY INVISIBLE (-6015 3835);
FORCEPROP 1 LASTPIN (-6025 3825) BN 1
J 2
(-6013 3833);
DISPLAY 0.489362 (-6013 3833);
PAINT GREEN (-6013 3833);
FORCEPROP 2 LAST CDS_LIB mstr_standard
J 0
(-6075 3825);
DISPLAY 0.723404 (-6075 3825);
PAINT MONO (-6075 3825);
DISPLAY INVISIBLE (-6075 3825);
FORCEPROP 1 LAST BODY_TYPE PLUMBING
J 2
(-6075 3875);
DISPLAY 0.872340 (-6075 3875);
PAINT GREEN (-6075 3875);
DISPLAY INVISIBLE (-6075 3875);
FORCEPROP 1 LAST HDL_TAP TRUE
J 2
(-6400 3700);
DISPLAY 0.872340 (-6400 3700);
DISPLAY INVISIBLE (-6400 3700);
FORCEPROP 1 LAST PATH I289
J 2
(-6073 3825);
DISPLAY 0.872340 (-6073 3825);
PAINT GREEN (-6073 3825);
DISPLAY INVISIBLE (-6073 3825);
FORCEADD TAP..1
R 2
(-6075 3725);
FORCEPROP 3 LASTPIN (-6025 3725) SIG_NAME M_B_CPU1_SA_CA<3>
J 0
(-6015 3735);
DISPLAY 0.659574 (-6015 3735);
PAINT MONO (-6015 3735);
DISPLAY INVISIBLE (-6015 3735);
FORCEPROP 1 LASTPIN (-6025 3725) BN 3
J 2
(-6013 3733);
DISPLAY 0.489362 (-6013 3733);
PAINT GREEN (-6013 3733);
FORCEPROP 2 LAST CDS_LIB mstr_standard
J 0
(-6075 3725);
DISPLAY 0.723404 (-6075 3725);
PAINT MONO (-6075 3725);
DISPLAY INVISIBLE (-6075 3725);
FORCEPROP 1 LAST BODY_TYPE PLUMBING
J 2
(-6075 3775);
DISPLAY 0.872340 (-6075 3775);
PAINT GREEN (-6075 3775);
DISPLAY INVISIBLE (-6075 3775);
FORCEPROP 1 LAST HDL_TAP TRUE
J 2
(-6400 3600);
DISPLAY 0.872340 (-6400 3600);
DISPLAY INVISIBLE (-6400 3600);
FORCEPROP 1 LAST PATH I290
J 2
(-6073 3725);
DISPLAY 0.872340 (-6073 3725);
PAINT GREEN (-6073 3725);
DISPLAY INVISIBLE (-6073 3725);
FORCEADD TAP..1
R 2
(-6075 3775);
FORCEPROP 3 LASTPIN (-6025 3775) SIG_NAME M_B_CPU1_SA_CA<2>
J 0
(-6015 3785);
DISPLAY 0.659574 (-6015 3785);
PAINT MONO (-6015 3785);
DISPLAY INVISIBLE (-6015 3785);
FORCEPROP 1 LASTPIN (-6025 3775) BN 2
J 2
(-6013 3783);
DISPLAY 0.489362 (-6013 3783);
PAINT GREEN (-6013 3783);
FORCEPROP 2 LAST CDS_LIB mstr_standard
J 0
(-6075 3775);
DISPLAY 0.723404 (-6075 3775);
PAINT MONO (-6075 3775);
DISPLAY INVISIBLE (-6075 3775);
FORCEPROP 1 LAST BODY_TYPE PLUMBING
J 2
(-6075 3825);
DISPLAY 0.872340 (-6075 3825);
PAINT GREEN (-6075 3825);
DISPLAY INVISIBLE (-6075 3825);
FORCEPROP 1 LAST HDL_TAP TRUE
J 2
(-6400 3650);
DISPLAY 0.872340 (-6400 3650);
DISPLAY INVISIBLE (-6400 3650);
FORCEPROP 1 LAST PATH I291
J 2
(-6073 3775);
DISPLAY 0.872340 (-6073 3775);
PAINT GREEN (-6073 3775);
DISPLAY INVISIBLE (-6073 3775);
FORCEADD TAP..1
R 2
(-6075 3675);
FORCEPROP 3 LASTPIN (-6025 3675) SIG_NAME M_B_CPU1_SA_CA<4>
J 0
(-6015 3685);
DISPLAY 0.659574 (-6015 3685);
PAINT MONO (-6015 3685);
DISPLAY INVISIBLE (-6015 3685);
FORCEPROP 1 LASTPIN (-6025 3675) BN 4
J 2
(-6013 3683);
DISPLAY 0.489362 (-6013 3683);
PAINT GREEN (-6013 3683);
FORCEPROP 2 LAST CDS_LIB mstr_standard
J 0
(-6075 3675);
DISPLAY 0.723404 (-6075 3675);
PAINT MONO (-6075 3675);
DISPLAY INVISIBLE (-6075 3675);
FORCEPROP 1 LAST BODY_TYPE PLUMBING
J 2
(-6075 3725);
DISPLAY 0.872340 (-6075 3725);
PAINT GREEN (-6075 3725);
DISPLAY INVISIBLE (-6075 3725);
FORCEPROP 1 LAST HDL_TAP TRUE
J 2
(-6400 3550);
DISPLAY 0.872340 (-6400 3550);
DISPLAY INVISIBLE (-6400 3550);
FORCEPROP 1 LAST PATH I292
J 2
(-6073 3675);
DISPLAY 0.872340 (-6073 3675);
PAINT GREEN (-6073 3675);
DISPLAY INVISIBLE (-6073 3675);
FORCEADD TAP..1
R 2
(-6075 3625);
FORCEPROP 3 LASTPIN (-6025 3625) SIG_NAME M_B_CPU1_SA_CA<5>
J 0
(-6015 3635);
DISPLAY 0.659574 (-6015 3635);
PAINT MONO (-6015 3635);
DISPLAY INVISIBLE (-6015 3635);
FORCEPROP 1 LASTPIN (-6025 3625) BN 5
J 2
(-6013 3633);
DISPLAY 0.489362 (-6013 3633);
PAINT GREEN (-6013 3633);
FORCEPROP 2 LAST CDS_LIB mstr_standard
J 0
(-6075 3625);
DISPLAY 0.723404 (-6075 3625);
PAINT MONO (-6075 3625);
DISPLAY INVISIBLE (-6075 3625);
FORCEPROP 1 LAST BODY_TYPE PLUMBING
J 2
(-6075 3675);
DISPLAY 0.872340 (-6075 3675);
PAINT GREEN (-6075 3675);
DISPLAY INVISIBLE (-6075 3675);
FORCEPROP 1 LAST HDL_TAP TRUE
J 2
(-6400 3500);
DISPLAY 0.872340 (-6400 3500);
DISPLAY INVISIBLE (-6400 3500);
FORCEPROP 1 LAST PATH I293
J 2
(-6073 3625);
DISPLAY 0.872340 (-6073 3625);
PAINT GREEN (-6073 3625);
DISPLAY INVISIBLE (-6073 3625);
FORCEADD TAP..1
R 2
(-6075 3575);
FORCEPROP 3 LASTPIN (-6025 3575) SIG_NAME M_B_CPU1_SA_CA<6>
J 0
(-6015 3585);
DISPLAY 0.659574 (-6015 3585);
PAINT MONO (-6015 3585);
DISPLAY INVISIBLE (-6015 3585);
FORCEPROP 1 LASTPIN (-6025 3575) BN 6
J 2
(-6013 3583);
DISPLAY 0.489362 (-6013 3583);
PAINT GREEN (-6013 3583);
FORCEPROP 2 LAST CDS_LIB mstr_standard
J 0
(-6075 3575);
DISPLAY 0.723404 (-6075 3575);
PAINT MONO (-6075 3575);
DISPLAY INVISIBLE (-6075 3575);
FORCEPROP 1 LAST BODY_TYPE PLUMBING
J 2
(-6075 3625);
DISPLAY 0.872340 (-6075 3625);
PAINT GREEN (-6075 3625);
DISPLAY INVISIBLE (-6075 3625);
FORCEPROP 1 LAST HDL_TAP TRUE
J 2
(-6400 3450);
DISPLAY 0.872340 (-6400 3450);
DISPLAY INVISIBLE (-6400 3450);
FORCEPROP 1 LAST PATH I294
J 2
(-6073 3575);
DISPLAY 0.872340 (-6073 3575);
PAINT GREEN (-6073 3575);
DISPLAY INVISIBLE (-6073 3575);
FORCEADD TAP..1
R 2
(-6075 3425);
FORCEPROP 3 LASTPIN (-6025 3425) SIG_NAME M_B_CPU1_SB_CA<1>
J 0
(-6015 3435);
DISPLAY 0.659574 (-6015 3435);
PAINT MONO (-6015 3435);
DISPLAY INVISIBLE (-6015 3435);
FORCEPROP 1 LASTPIN (-6025 3425) BN 1
J 2
(-6013 3433);
DISPLAY 0.489362 (-6013 3433);
PAINT GREEN (-6013 3433);
FORCEPROP 2 LAST CDS_LIB mstr_standard
J 0
(-6075 3425);
DISPLAY 0.723404 (-6075 3425);
PAINT MONO (-6075 3425);
DISPLAY INVISIBLE (-6075 3425);
FORCEPROP 1 LAST BODY_TYPE PLUMBING
J 2
(-6075 3475);
DISPLAY 0.872340 (-6075 3475);
PAINT GREEN (-6075 3475);
DISPLAY INVISIBLE (-6075 3475);
FORCEPROP 1 LAST HDL_TAP TRUE
J 2
(-6400 3300);
DISPLAY 0.872340 (-6400 3300);
DISPLAY INVISIBLE (-6400 3300);
FORCEPROP 1 LAST PATH I295
J 2
(-6073 3425);
DISPLAY 0.872340 (-6073 3425);
PAINT GREEN (-6073 3425);
DISPLAY INVISIBLE (-6073 3425);
FORCEADD TAP..1
R 2
(-6075 3475);
FORCEPROP 3 LASTPIN (-6025 3475) SIG_NAME M_B_CPU1_SB_CA<0>
J 0
(-6015 3485);
DISPLAY 0.659574 (-6015 3485);
PAINT MONO (-6015 3485);
DISPLAY INVISIBLE (-6015 3485);
FORCEPROP 1 LASTPIN (-6025 3475) BN 0
J 2
(-6013 3483);
DISPLAY 0.489362 (-6013 3483);
PAINT GREEN (-6013 3483);
FORCEPROP 2 LAST CDS_LIB mstr_standard
J 0
(-6075 3475);
DISPLAY 0.723404 (-6075 3475);
PAINT MONO (-6075 3475);
DISPLAY INVISIBLE (-6075 3475);
FORCEPROP 1 LAST BODY_TYPE PLUMBING
J 2
(-6075 3525);
DISPLAY 0.872340 (-6075 3525);
PAINT GREEN (-6075 3525);
DISPLAY INVISIBLE (-6075 3525);
FORCEPROP 1 LAST HDL_TAP TRUE
J 2
(-6400 3350);
DISPLAY 0.872340 (-6400 3350);
DISPLAY INVISIBLE (-6400 3350);
FORCEPROP 1 LAST PATH I296
J 2
(-6073 3475);
DISPLAY 0.872340 (-6073 3475);
PAINT GREEN (-6073 3475);
DISPLAY INVISIBLE (-6073 3475);
FORCEADD TAP..1
R 2
(-6075 3375);
FORCEPROP 3 LASTPIN (-6025 3375) SIG_NAME M_B_CPU1_SB_CA<2>
J 0
(-6015 3385);
DISPLAY 0.659574 (-6015 3385);
PAINT MONO (-6015 3385);
DISPLAY INVISIBLE (-6015 3385);
FORCEPROP 1 LASTPIN (-6025 3375) BN 2
J 2
(-6013 3383);
DISPLAY 0.489362 (-6013 3383);
PAINT GREEN (-6013 3383);
FORCEPROP 2 LAST CDS_LIB mstr_standard
J 0
(-6075 3375);
DISPLAY 0.723404 (-6075 3375);
PAINT MONO (-6075 3375);
DISPLAY INVISIBLE (-6075 3375);
FORCEPROP 1 LAST BODY_TYPE PLUMBING
J 2
(-6075 3425);
DISPLAY 0.872340 (-6075 3425);
PAINT GREEN (-6075 3425);
DISPLAY INVISIBLE (-6075 3425);
FORCEPROP 1 LAST HDL_TAP TRUE
J 2
(-6400 3250);
DISPLAY 0.872340 (-6400 3250);
DISPLAY INVISIBLE (-6400 3250);
FORCEPROP 1 LAST PATH I297
J 2
(-6073 3375);
DISPLAY 0.872340 (-6073 3375);
PAINT GREEN (-6073 3375);
DISPLAY INVISIBLE (-6073 3375);
FORCEADD TAP..1
R 2
(-6075 3325);
FORCEPROP 3 LASTPIN (-6025 3325) SIG_NAME M_B_CPU1_SB_CA<3>
J 0
(-6015 3335);
DISPLAY 0.659574 (-6015 3335);
PAINT MONO (-6015 3335);
DISPLAY INVISIBLE (-6015 3335);
FORCEPROP 1 LASTPIN (-6025 3325) BN 3
J 2
(-6013 3333);
DISPLAY 0.489362 (-6013 3333);
PAINT GREEN (-6013 3333);
FORCEPROP 2 LAST CDS_LIB mstr_standard
J 0
(-6075 3325);
DISPLAY 0.723404 (-6075 3325);
PAINT MONO (-6075 3325);
DISPLAY INVISIBLE (-6075 3325);
FORCEPROP 1 LAST BODY_TYPE PLUMBING
J 2
(-6075 3375);
DISPLAY 0.872340 (-6075 3375);
PAINT GREEN (-6075 3375);
DISPLAY INVISIBLE (-6075 3375);
FORCEPROP 1 LAST HDL_TAP TRUE
J 2
(-6400 3200);
DISPLAY 0.872340 (-6400 3200);
DISPLAY INVISIBLE (-6400 3200);
FORCEPROP 1 LAST PATH I298
J 2
(-6073 3325);
DISPLAY 0.872340 (-6073 3325);
PAINT GREEN (-6073 3325);
DISPLAY INVISIBLE (-6073 3325);
FORCEADD TAP..1
R 2
(-6075 3175);
FORCEPROP 3 LASTPIN (-6025 3175) SIG_NAME M_B_CPU1_SB_CA<6>
J 0
(-6015 3185);
DISPLAY 0.659574 (-6015 3185);
PAINT MONO (-6015 3185);
DISPLAY INVISIBLE (-6015 3185);
FORCEPROP 1 LASTPIN (-6025 3175) BN 6
J 2
(-6013 3183);
DISPLAY 0.489362 (-6013 3183);
PAINT GREEN (-6013 3183);
FORCEPROP 2 LAST CDS_LIB mstr_standard
J 0
(-6075 3175);
DISPLAY 0.723404 (-6075 3175);
PAINT MONO (-6075 3175);
DISPLAY INVISIBLE (-6075 3175);
FORCEPROP 1 LAST BODY_TYPE PLUMBING
J 2
(-6075 3225);
DISPLAY 0.872340 (-6075 3225);
PAINT GREEN (-6075 3225);
DISPLAY INVISIBLE (-6075 3225);
FORCEPROP 1 LAST HDL_TAP TRUE
J 2
(-6400 3050);
DISPLAY 0.872340 (-6400 3050);
DISPLAY INVISIBLE (-6400 3050);
FORCEPROP 1 LAST PATH I299
J 2
(-6073 3175);
DISPLAY 0.872340 (-6073 3175);
PAINT GREEN (-6073 3175);
DISPLAY INVISIBLE (-6073 3175);
FORCEADD TAP..1
R 2
(-6075 3275);
FORCEPROP 3 LASTPIN (-6025 3275) SIG_NAME M_B_CPU1_SB_CA<4>
J 0
(-6015 3285);
DISPLAY 0.659574 (-6015 3285);
PAINT MONO (-6015 3285);
DISPLAY INVISIBLE (-6015 3285);
FORCEPROP 1 LASTPIN (-6025 3275) BN 4
J 2
(-6013 3283);
DISPLAY 0.489362 (-6013 3283);
PAINT GREEN (-6013 3283);
FORCEPROP 2 LAST CDS_LIB mstr_standard
J 0
(-6075 3275);
DISPLAY 0.723404 (-6075 3275);
PAINT MONO (-6075 3275);
DISPLAY INVISIBLE (-6075 3275);
FORCEPROP 1 LAST BODY_TYPE PLUMBING
J 2
(-6075 3325);
DISPLAY 0.872340 (-6075 3325);
PAINT GREEN (-6075 3325);
DISPLAY INVISIBLE (-6075 3325);
FORCEPROP 1 LAST HDL_TAP TRUE
J 2
(-6400 3150);
DISPLAY 0.872340 (-6400 3150);
DISPLAY INVISIBLE (-6400 3150);
FORCEPROP 1 LAST PATH I300
J 2
(-6073 3275);
DISPLAY 0.872340 (-6073 3275);
PAINT GREEN (-6073 3275);
DISPLAY INVISIBLE (-6073 3275);
FORCEADD TAP..1
R 2
(-6075 3225);
FORCEPROP 3 LASTPIN (-6025 3225) SIG_NAME M_B_CPU1_SB_CA<5>
J 0
(-6015 3235);
DISPLAY 0.659574 (-6015 3235);
PAINT MONO (-6015 3235);
DISPLAY INVISIBLE (-6015 3235);
FORCEPROP 1 LASTPIN (-6025 3225) BN 5
J 2
(-6013 3233);
DISPLAY 0.489362 (-6013 3233);
PAINT GREEN (-6013 3233);
FORCEPROP 2 LAST CDS_LIB mstr_standard
J 0
(-6075 3225);
DISPLAY 0.723404 (-6075 3225);
PAINT MONO (-6075 3225);
DISPLAY INVISIBLE (-6075 3225);
FORCEPROP 1 LAST BODY_TYPE PLUMBING
J 2
(-6075 3275);
DISPLAY 0.872340 (-6075 3275);
PAINT GREEN (-6075 3275);
DISPLAY INVISIBLE (-6075 3275);
FORCEPROP 1 LAST HDL_TAP TRUE
J 2
(-6400 3100);
DISPLAY 0.872340 (-6400 3100);
DISPLAY INVISIBLE (-6400 3100);
FORCEPROP 1 LAST PATH I301
J 2
(-6073 3225);
DISPLAY 0.872340 (-6073 3225);
PAINT GREEN (-6073 3225);
DISPLAY INVISIBLE (-6073 3225);
FORCEADD OFFPAGE..2
R 2
(-6675 3900);
FORCEPROP 2 LAST $XR0 98 
J 0
(-6899 3900);
DISPLAY 0.638298 (-6899 3900);
PAINT MONO (-6899 3900);
FORCEPROP 2 LAST PATH I302
J 0
(-6925 3950);
DISPLAY 1.021277 (-6925 3950);
DISPLAY INVISIBLE (-6925 3950);
FORCEPROP 1 LAST COMMENT_BODY TRUE
J 2
(-6630 3805);
DISPLAY 0.872340 (-6630 3805);
PAINT GREEN (-6630 3805);
DISPLAY INVISIBLE (-6630 3805);
FORCEPROP 1 LAST OFFPAGE TRUE
J 2
(-7000 3775);
DISPLAY 0.872340 (-7000 3775);
PAINT GREEN (-7000 3775);
DISPLAY INVISIBLE (-7000 3775);
FORCEPROP 2 LAST CDS_LIB standard
J 0
(-6675 3900);
DISPLAY INVISIBLE (-6675 3900);
FORCEADD OFFPAGE..2
R 2
(-6675 3500);
FORCEPROP 2 LAST $XR0 98 
J 0
(-6899 3500);
DISPLAY 0.638298 (-6899 3500);
PAINT MONO (-6899 3500);
FORCEPROP 2 LAST PATH I303
J 0
(-6925 3550);
DISPLAY 1.021277 (-6925 3550);
DISPLAY INVISIBLE (-6925 3550);
FORCEPROP 1 LAST COMMENT_BODY TRUE
J 2
(-6630 3405);
DISPLAY 0.872340 (-6630 3405);
PAINT GREEN (-6630 3405);
DISPLAY INVISIBLE (-6630 3405);
FORCEPROP 1 LAST OFFPAGE TRUE
J 2
(-7000 3375);
DISPLAY 0.872340 (-7000 3375);
PAINT GREEN (-7000 3375);
DISPLAY INVISIBLE (-7000 3375);
FORCEPROP 2 LAST CDS_LIB standard
J 0
(-6675 3500);
DISPLAY INVISIBLE (-6675 3500);
FORCEADD OFFPAGE..2
R 2
(-6675 3025);
FORCEPROP 2 LAST $XR0 98 
J 0
(-6899 3025);
DISPLAY 0.638298 (-6899 3025);
PAINT MONO (-6899 3025);
FORCEPROP 2 LAST PATH I304
J 0
(-6925 3075);
DISPLAY 1.021277 (-6925 3075);
DISPLAY INVISIBLE (-6925 3075);
FORCEPROP 1 LAST COMMENT_BODY TRUE
J 2
(-6630 2930);
DISPLAY 0.872340 (-6630 2930);
PAINT GREEN (-6630 2930);
DISPLAY INVISIBLE (-6630 2930);
FORCEPROP 1 LAST OFFPAGE TRUE
J 2
(-7000 2900);
DISPLAY 0.872340 (-7000 2900);
PAINT GREEN (-7000 2900);
DISPLAY INVISIBLE (-7000 2900);
FORCEPROP 2 LAST CDS_LIB standard
J 0
(-6675 3025);
DISPLAY INVISIBLE (-6675 3025);
FORCEADD OFFPAGE..2
R 2
(-6675 2975);
FORCEPROP 2 LAST $XR0 98 
J 0
(-6899 2975);
DISPLAY 0.638298 (-6899 2975);
PAINT MONO (-6899 2975);
FORCEPROP 2 LAST PATH I305
J 0
(-6925 3025);
DISPLAY 1.021277 (-6925 3025);
DISPLAY INVISIBLE (-6925 3025);
FORCEPROP 1 LAST COMMENT_BODY TRUE
J 2
(-6630 2880);
DISPLAY 0.872340 (-6630 2880);
PAINT GREEN (-6630 2880);
DISPLAY INVISIBLE (-6630 2880);
FORCEPROP 1 LAST OFFPAGE TRUE
J 2
(-7000 2850);
DISPLAY 0.872340 (-7000 2850);
PAINT GREEN (-7000 2850);
DISPLAY INVISIBLE (-7000 2850);
FORCEPROP 2 LAST CDS_LIB standard
J 0
(-6675 2975);
DISPLAY INVISIBLE (-6675 2975);
FORCEADD OFFPAGE..2
R 2
(-6675 2875);
FORCEPROP 2 LAST $XR0 98 
J 0
(-6899 2875);
DISPLAY 0.638298 (-6899 2875);
PAINT MONO (-6899 2875);
FORCEPROP 2 LAST PATH I306
J 0
(-6925 2925);
DISPLAY 1.021277 (-6925 2925);
DISPLAY INVISIBLE (-6925 2925);
FORCEPROP 1 LAST COMMENT_BODY TRUE
J 2
(-6630 2780);
DISPLAY 0.872340 (-6630 2780);
PAINT GREEN (-6630 2780);
DISPLAY INVISIBLE (-6630 2780);
FORCEPROP 1 LAST OFFPAGE TRUE
J 2
(-7000 2750);
DISPLAY 0.872340 (-7000 2750);
PAINT GREEN (-7000 2750);
DISPLAY INVISIBLE (-7000 2750);
FORCEPROP 2 LAST CDS_LIB standard
J 0
(-6675 2875);
DISPLAY INVISIBLE (-6675 2875);
FORCEADD OFFPAGE..2
R 2
(-6675 2825);
FORCEPROP 2 LAST $XR0 98 
J 0
(-6899 2825);
DISPLAY 0.638298 (-6899 2825);
PAINT MONO (-6899 2825);
FORCEPROP 2 LAST PATH I307
J 0
(-6925 2875);
DISPLAY 1.021277 (-6925 2875);
DISPLAY INVISIBLE (-6925 2875);
FORCEPROP 1 LAST COMMENT_BODY TRUE
J 2
(-6630 2730);
DISPLAY 0.872340 (-6630 2730);
PAINT GREEN (-6630 2730);
DISPLAY INVISIBLE (-6630 2730);
FORCEPROP 1 LAST OFFPAGE TRUE
J 2
(-7000 2700);
DISPLAY 0.872340 (-7000 2700);
PAINT GREEN (-7000 2700);
DISPLAY INVISIBLE (-7000 2700);
FORCEPROP 2 LAST CDS_LIB standard
J 0
(-6675 2825);
DISPLAY INVISIBLE (-6675 2825);
FORCEADD OFFPAGE..1
(-6675 2725);
FORCEPROP 2 LAST $XR0 98 
J 0
(-6926 2725);
DISPLAY 0.638298 (-6926 2725);
PAINT MONO (-6926 2725);
FORCEPROP 2 LAST PATH I308
J 0
(-6950 2775);
DISPLAY 1.021277 (-6950 2775);
DISPLAY INVISIBLE (-6950 2775);
FORCEPROP 1 LAST COMMENT_BODY TRUE
J 0
(-6550 2625);
DISPLAY 0.872340 (-6550 2625);
PAINT GREEN (-6550 2625);
DISPLAY INVISIBLE (-6550 2625);
FORCEPROP 1 LAST OFFPAGE TRUE
J 0
(-6350 2600);
DISPLAY 0.872340 (-6350 2600);
PAINT GREEN (-6350 2600);
DISPLAY INVISIBLE (-6350 2600);
FORCEPROP 2 LAST CDS_LIB standard
J 0
(-6675 2725);
DISPLAY INVISIBLE (-6675 2725);
FORCEADD OFFPAGE..5
(-6675 2625);
FORCEPROP 2 LAST $XR0 98 
J 0
(-6899 2625);
DISPLAY 0.638298 (-6899 2625);
PAINT MONO (-6899 2625);
FORCEPROP 2 LAST PATH I309
J 0
(-6925 2675);
DISPLAY 1.021277 (-6925 2675);
DISPLAY INVISIBLE (-6925 2675);
FORCEPROP 1 LAST COMMENT_BODY TRUE
J 0
(-6575 2550);
DISPLAY 0.872340 (-6575 2550);
PAINT GREEN (-6575 2550);
DISPLAY INVISIBLE (-6575 2550);
FORCEPROP 1 LAST OFFPAGE TRUE
J 0
(-6350 2500);
DISPLAY 0.872340 (-6350 2500);
PAINT GREEN (-6350 2500);
DISPLAY INVISIBLE (-6350 2500);
FORCEPROP 2 LAST CDS_LIB mstr_standard
J 0
(-6675 2625);
DISPLAY INVISIBLE (-6675 2625);
FORCEADD OFFPAGE..2
R 2
(-6675 2475);
FORCEPROP 2 LAST $XR0 98 
J 0
(-6899 2475);
DISPLAY 0.638298 (-6899 2475);
PAINT MONO (-6899 2475);
FORCEPROP 2 LAST PATH I310
J 0
(-6925 2525);
DISPLAY 1.021277 (-6925 2525);
DISPLAY INVISIBLE (-6925 2525);
FORCEPROP 1 LAST COMMENT_BODY TRUE
J 2
(-6630 2380);
DISPLAY 0.872340 (-6630 2380);
PAINT GREEN (-6630 2380);
DISPLAY INVISIBLE (-6630 2380);
FORCEPROP 1 LAST OFFPAGE TRUE
J 2
(-7000 2350);
DISPLAY 0.872340 (-7000 2350);
PAINT GREEN (-7000 2350);
DISPLAY INVISIBLE (-7000 2350);
FORCEPROP 2 LAST CDS_LIB standard
J 0
(-6675 2475);
DISPLAY INVISIBLE (-6675 2475);
FORCEADD OFFPAGE..2
R 2
(-6675 2525);
FORCEPROP 2 LAST $XR0 98 
J 0
(-6899 2525);
DISPLAY 0.638298 (-6899 2525);
PAINT MONO (-6899 2525);
FORCEPROP 2 LAST PATH I311
J 0
(-6925 2575);
DISPLAY 1.021277 (-6925 2575);
DISPLAY INVISIBLE (-6925 2575);
FORCEPROP 1 LAST COMMENT_BODY TRUE
J 2
(-6630 2430);
DISPLAY 0.872340 (-6630 2430);
PAINT GREEN (-6630 2430);
DISPLAY INVISIBLE (-6630 2430);
FORCEPROP 1 LAST OFFPAGE TRUE
J 2
(-7000 2400);
DISPLAY 0.872340 (-7000 2400);
PAINT GREEN (-7000 2400);
DISPLAY INVISIBLE (-7000 2400);
FORCEPROP 2 LAST CDS_LIB standard
J 0
(-6675 2525);
DISPLAY INVISIBLE (-6675 2525);
FORCEADD OFFPAGE..1
(-6675 2375);
FORCEPROP 2 LAST $XR0 98 
J 0
(-6926 2375);
DISPLAY 0.638298 (-6926 2375);
PAINT MONO (-6926 2375);
FORCEPROP 2 LAST PATH I312
J 0
(-6950 2425);
DISPLAY 1.021277 (-6950 2425);
DISPLAY INVISIBLE (-6950 2425);
FORCEPROP 1 LAST COMMENT_BODY TRUE
J 0
(-6550 2275);
DISPLAY 0.872340 (-6550 2275);
PAINT GREEN (-6550 2275);
DISPLAY INVISIBLE (-6550 2275);
FORCEPROP 1 LAST OFFPAGE TRUE
J 0
(-6350 2250);
DISPLAY 0.872340 (-6350 2250);
PAINT GREEN (-6350 2250);
DISPLAY INVISIBLE (-6350 2250);
FORCEPROP 2 LAST CDS_LIB standard
J 0
(-6675 2375);
DISPLAY INVISIBLE (-6675 2375);
FORCEADD OFFPAGE..5
(-6675 2275);
FORCEPROP 2 LAST $XR0 98 
J 0
(-6899 2275);
DISPLAY 0.638298 (-6899 2275);
PAINT MONO (-6899 2275);
FORCEPROP 2 LAST PATH I313
J 0
(-6925 2325);
DISPLAY 1.021277 (-6925 2325);
DISPLAY INVISIBLE (-6925 2325);
FORCEPROP 1 LAST COMMENT_BODY TRUE
J 0
(-6575 2200);
DISPLAY 0.872340 (-6575 2200);
PAINT GREEN (-6575 2200);
DISPLAY INVISIBLE (-6575 2200);
FORCEPROP 1 LAST OFFPAGE TRUE
J 0
(-6350 2150);
DISPLAY 0.872340 (-6350 2150);
PAINT GREEN (-6350 2150);
DISPLAY INVISIBLE (-6350 2150);
FORCEPROP 2 LAST CDS_LIB standard
J 0
(-6675 2275);
DISPLAY INVISIBLE (-6675 2275);
FORCEADD Q_RES..1
(-6750 2175);
FORCEPROP 1 LAST LOCATION R501
J 0
(-7075 2175);
DISPLAY 0.489362 (-7075 2175);
PAINT SKYBLUE (-7075 2175);
FORCEPROP 0 LAST $SEC 1
J 0
(-6925 2225);
DISPLAY 0.680851 (-6925 2225);
PAINT MONO (-6925 2225);
DISPLAY INVISIBLE (-6925 2225);
FORCEPROP 0 LAST CDS_SEC 1
J 0
(-6925 2225);
DISPLAY 1.021277 (-6925 2225);
DISPLAY INVISIBLE (-6925 2225);
FORCEPROP 1 LASTPIN (-6850 2175) $PN 1
J 0
(-6838 2187);
DISPLAY 0.489362 (-6838 2187);
PAINT MONO (-6838 2187);
FORCEPROP 1 LASTPIN (-6650 2175) $PN 2
J 0
(-6688 2187);
DISPLAY 0.489362 (-6688 2187);
PAINT MONO (-6688 2187);
FORCEPROP 1 LAST TOLERANCE 1%
J 0
(-6475 2175);
DISPLAY 0.489362 (-6475 2175);
PAINT SKYBLUE (-6475 2175);
FORCEPROP 1 LAST VALUE 15   
J 2
(-6425 2175);
DISPLAY 0.489362 (-6425 2175);
PAINT SKYBLUE (-6425 2175);
FORCEPROP 1 LAST PART_NUMBER CS01502FB11
J 0
(-6625 2150);
DISPLAY 0.489362 (-6625 2150);
PAINT SKYBLUE (-6625 2150);
FORCEPROP 1 LAST PACK_TYPE 0402LF
J 0
(-7075 2150);
DISPLAY 0.489362 (-7075 2150);
PAINT SKYBLUE (-7075 2150);
FORCEPROP 2 LAST CDS_LIB pure_quanta
J 0
(-6750 2175);
DISPLAY INVISIBLE (-6750 2175);
FORCEPROP 1 LAST PATH I314
J 0
(-6800 2325);
DISPLAY 0.978723 (-6800 2325);
PAINT WHITE (-6800 2325);
DISPLAY INVISIBLE (-6800 2325);
FORCEPROP 1 LAST WATTAGE 1/16W
J 2
(-6525 2300);
DISPLAY 0.638298 (-6525 2300);
PAINT SKYBLUE (-6525 2300);
DISPLAY INVISIBLE (-6525 2300);
FORCEPROP 1 LAST MATERIAL CHIP
J 0
(-6875 2300);
DISPLAY 0.638298 (-6875 2300);
PAINT SKYBLUE (-6875 2300);
DISPLAY INVISIBLE (-6875 2300);
FORCEADD OFFPAGE..1
(-7625 2175);
FORCEPROP 2 LAST $XR0 98 
J 0
(-7846 2175);
DISPLAY 0.638298 (-7846 2175);
PAINT MONO (-7846 2175);
FORCEPROP 2 LAST PATH I315
J 0
(-7875 2225);
DISPLAY 1.021277 (-7875 2225);
DISPLAY INVISIBLE (-7875 2225);
FORCEPROP 1 LAST COMMENT_BODY TRUE
J 0
(-7500 2075);
DISPLAY 0.872340 (-7500 2075);
PAINT GREEN (-7500 2075);
DISPLAY INVISIBLE (-7500 2075);
FORCEPROP 1 LAST OFFPAGE TRUE
J 0
(-7300 2050);
DISPLAY 0.872340 (-7300 2050);
PAINT GREEN (-7300 2050);
DISPLAY INVISIBLE (-7300 2050);
FORCEPROP 2 LAST CDS_LIB mstr_standard
J 0
(-7625 2175);
DISPLAY INVISIBLE (-7625 2175);
FORCEADD OFFPAGE..5
(-6675 2075);
FORCEPROP 2 LAST $XR0 98 
J 0
(-6899 2075);
DISPLAY 0.638298 (-6899 2075);
PAINT MONO (-6899 2075);
FORCEPROP 2 LAST PATH I316
J 0
(-6925 2125);
DISPLAY 1.021277 (-6925 2125);
DISPLAY INVISIBLE (-6925 2125);
FORCEPROP 1 LAST COMMENT_BODY TRUE
J 0
(-6575 2000);
DISPLAY 0.872340 (-6575 2000);
PAINT GREEN (-6575 2000);
DISPLAY INVISIBLE (-6575 2000);
FORCEPROP 1 LAST OFFPAGE TRUE
J 0
(-6350 1950);
DISPLAY 0.872340 (-6350 1950);
PAINT GREEN (-6350 1950);
DISPLAY INVISIBLE (-6350 1950);
FORCEPROP 2 LAST CDS_LIB standard
J 0
(-6675 2075);
DISPLAY INVISIBLE (-6675 2075);
FORCEADD CAD_NOTE..1
(-7775 2450);
FORCEPROP 0 LAST L1 R1959 PLACE CLOSE TO CPU < 25MM
J 0
(-7925 2325);
DISPLAY 0.617021 (-7925 2325);
PAINT WHITE (-7925 2325);
FORCEPROP 2 LAST CDS_LIB pure_quanta_power
J 0
(-7775 2450);
DISPLAY INVISIBLE (-7775 2450);
FORCEPROP 1 LAST COMMENT_BODY TRUE
J 0
(-7750 2550);
DISPLAY 0.574468 (-7750 2550);
PAINT WHITE (-7750 2550);
DISPLAY INVISIBLE (-7750 2550);
FORCEADD QUANTA_TITLE_BLOCK_C..1
(-100 100);
FORCEPROP 0 LAST CDS_CON_LAST_MODIFIED Fri Mar 11 14:52:29 2022
J 0
(-1985 115);
DISPLAY INVISIBLE (-1985 115);
FORCEPROP 1 LAST CUSTOM_TXT_CDS <CON_LAST_MODIFIED>
J 0
(-1985 115);
DISPLAY 0.978723 (-1985 115);
FORCEPROP 2 LAST CUSTOM_TXT_CDS <XR_PAGE_TITLE>
J 0
(-7990 5350);
DISPLAY 0.638298 (-7990 5350);
PAINT PINK (-7990 5350);
DISPLAY INVISIBLE (-7990 5350);
FORCEPROP 1 LAST CUSTOM_TXT_CDS <NAME_2>
J 0
(-3275 150);
FORCEPROP 1 LAST CUSTOM_TXT_CDS <NAME_1>
J 0
(-3275 275);
FORCEPROP 1 LAST CUSTOM_TXT_CDS <Q_NUMBER>
J 0
(-1503 203);
DISPLAY 1.212766 (-1503 203);
FORCEPROP 1 LAST CUSTOM_TXT_CDS <Q_PROJ>
J 0
(-2482 202);
DISPLAY 1.212766 (-2482 202);
FORCEPROP 1 LAST CUSTOM_TXT_CDS <Q_REV>
J 0
(-284 203);
DISPLAY 1.212766 (-284 203);
FORCEPROP 1 LAST CUSTOM_TXT_CDS <CON_PAGE_NUM> OF <CON_TOTAL_PAGES>
J 0
(-546 118);
DISPLAY 0.978723 (-546 118);
FORCEPROP 1 LAST Q_TITLE CPU1 DDR CHB
J 0
(-9400 150);
DISPLAY 2.446809 (-9400 150);
PAINT GREEN (-9400 150);
FORCEPROP 1 LAST Q_DEPT BU9
J 1
(-3863 149);
DISPLAY 1.957447 (-3863 149);
PAINT GREEN (-3863 149);
FORCEPROP 2 LAST PAGE_BORDER TRUE
J 0
(-7990 5350);
DISPLAY 0.638298 (-7990 5350);
PAINT PINK (-7990 5350);
DISPLAY INVISIBLE (-7990 5350);
FORCEPROP 2 LAST CDS_LIB pure_quanta
J 0
(-100 100);
DISPLAY INVISIBLE (-100 100);
FORCEPROP 1 LAST CDS_LMAN_SYM_OUTLINE -9475,6775,100,-125
J 0
(-100 100);
DISPLAY 0.468085 (-100 100);
PAINT GREEN (-100 100);
DISPLAY INVISIBLE (-100 100);
FORCEPROP 1 LAST COMMENT_BODY TRUE
J 0
(-88 87);
DISPLAY 0.978723 (-88 87);
PAINT GREEN (-88 87);
DISPLAY INVISIBLE (-88 87);
FORCEPROP 2 LAST CDS_XR_PAGE_TITLE CR-38 : @T6G_MB_LIB.T6G(SCH_1):PAGE38
J 0
(-7990 5350);
DISPLAY 0.638298 (-7990 5350);
PAINT PINK (-7990 5350);
DISPLAY INVISIBLE (-7990 5350);
WIRE 17 -1 (-3400 5450)(-3400 5400);
WIRE 17 -1 (-3400 5500)(-3400 5450);
WIRE 17 -1 (-3400 5400)(-3400 5350);
WIRE 17 -1 (-3400 5350)(-3400 5300);
WIRE 17 -1 (-3400 5550)(-3400 5500);
WIRE 17 -1 (-3400 5600)(-3400 5550);
WIRE 17 -1 (-3400 5300)(-3400 5250);
WIRE 17 -1 (-3400 5150)(-3400 5250);
WIRE 17 -1 (-3400 5700)(-3400 5600);
WIRE 17 -1 (-3400 5750)(-3400 5700);
WIRE 17 -1 (-3400 5100)(-3400 5150);
WIRE 17 -1 (-3400 5050)(-3400 5100);
WIRE 17 -1 (-3400 5800)(-3400 5750);
WIRE 17 -1 (-3400 5850)(-3400 5800);
WIRE 17 -1 (-3400 5000)(-3400 5050);
WIRE 17 -1 (-3400 5000)(-3400 4950);
WIRE 17 -1 (-3400 5900)(-3400 5850);
WIRE 17 -1 (-3400 5950)(-3400 5900);
WIRE 17 -1 (-3400 4950)(-3400 4900);
WIRE 17 -1 (-3400 4900)(-3400 4850);
WIRE 17 -1 (-3400 6000)(-3400 5950);
WIRE 17 -1 (-3400 6050)(-3400 6000);
WIRE 17 -1 (-3400 4850)(-3400 4800);
WIRE 17 -1 (-3400 4800)(-3400 4700);
WIRE 17 -1 (-3400 6050)(-2775 6050);
FORCEPROP 2 LAST SIG_NAME M_B_CPU1_SA_DQ<31:0>
J 2
(-2835 6060);
DISPLAY 0.489362 (-2835 6060);
WIRE 17 -1 (-3400 4700)(-3400 4650);
WIRE 17 -1 (-3400 4650)(-3400 4600);
WIRE 17 -1 (-3400 4600)(-3400 4550);
WIRE 17 -1 (-3400 4500)(-3400 4550);
WIRE 17 -1 (-3400 4450)(-3400 4500);
WIRE 17 -1 (-3400 4400)(-3400 4450);
WIRE 17 -1 (-3400 4350)(-3400 4400);
WIRE 17 -1 (-3400 4250)(-3400 4200);
WIRE 17 -1 (-3400 4250)(-2775 4250);
FORCEPROP 2 LAST SIG_NAME M_B_CPU1_SB_DQ<31:0>
J 2
(-2835 4260);
DISPLAY 0.489362 (-2835 4260);
WIRE 17 -1 (-3400 4200)(-3400 4150);
WIRE 17 -1 (-3400 4150)(-3400 4100);
WIRE 17 -1 (-3400 4100)(-3400 4050);
WIRE 17 -1 (-3400 4050)(-3400 4000);
WIRE 17 -1 (-3400 3100)(-3400 3050);
WIRE 17 -1 (-3400 3150)(-3400 3100);
WIRE 17 -1 (-3400 3050)(-3400 3000);
WIRE 17 -1 (-3400 3000)(-3400 2900);
WIRE 17 -1 (-3400 3200)(-3400 3150);
WIRE 17 -1 (-3400 3200)(-3400 3250);
WIRE 17 -1 (-3400 2900)(-3400 2850);
WIRE 17 -1 (-3400 2850)(-3400 2800);
WIRE 17 -1 (-3400 3250)(-3400 3300);
WIRE 17 -1 (-3400 3300)(-3400 3350);
WIRE 17 -1 (-3400 2800)(-3400 2750);
WIRE 17 -1 (-3400 2700)(-3400 2750);
WIRE 17 -1 (-3400 3350)(-3400 3450);
WIRE 17 -1 (-3400 3500)(-3400 3450);
WIRE 17 -1 (-3400 2650)(-3400 2700);
WIRE 17 -1 (-3400 2600)(-3400 2650);
WIRE 17 -1 (-3400 3550)(-3400 3500);
WIRE 17 -1 (-3400 3600)(-3400 3550);
WIRE 17 -1 (-3400 2550)(-3400 2600);
WIRE 17 -1 (-3400 3650)(-3400 3600);
WIRE 17 -1 (-3400 3700)(-3400 3650);
WIRE 17 -1 (-3400 3750)(-3400 3700);
WIRE 17 -1 (-3400 3800)(-3400 3750);
WIRE 17 -1 (-3400 3900)(-3400 3800);
WIRE 17 -1 (-3400 3950)(-3400 3900);
WIRE 17 -1 (-3400 4000)(-3400 3950);
WIRE 17 -1 (-3400 2350)(-3400 2300);
WIRE 17 -1 (-3400 2350)(-3400 2400);
WIRE 17 -1 (-3400 2250)(-3400 2300);
WIRE 17 -1 (-3400 2200)(-3400 2250);
WIRE 17 -1 (-3400 2450)(-3400 2400);
WIRE 17 -1 (-3400 2450)(-3400 2475);
WIRE 17 -1 (-3400 2150)(-3400 2200);
WIRE 17 -1 (-3400 2100)(-3400 2150);
WIRE 17 -1 (-3400 2475)(-2900 2475);
FORCEPROP 2 LAST SIG_NAME M_B_CPU1_SA_CB<7:0>
J 2
(-2900 2485);
DISPLAY 0.489362 (-2900 2485);
WIRE 17 -1 (-3400 2000)(-3400 1950);
WIRE 17 -1 (-3400 2000)(-3400 2025);
WIRE 17 -1 (-3400 1900)(-3400 1950);
WIRE 17 -1 (-3400 1900)(-3400 1850);
WIRE 17 -1 (-3400 2025)(-2900 2025);
FORCEPROP 2 LAST SIG_NAME M_B_CPU1_SB_CB<7:0>
J 2
(-2900 2035);
DISPLAY 0.489362 (-2900 2035);
WIRE 17 -1 (-3400 1800)(-3400 1850);
WIRE 17 -1 (-3400 1750)(-3400 1800);
WIRE 17 -1 (-3400 1700)(-3400 1750);
WIRE 17 -1 (-3400 1650)(-3400 1700);
WIRE 17 -1 (-6125 6000)(-6125 5900);
FORCEPROP 2 LAST SIG_NAME M_B_CPU1_SA_DQS_DN<9:0>
J 2
(-6160 6010);
DISPLAY 0.489362 (-6160 6010);
WIRE 17 -1 (-6125 5800)(-6125 5700);
WIRE 17 -1 (-6125 5900)(-6125 5800);
WIRE 17 -1 (-6125 5700)(-6125 5600);
WIRE 17 -1 (-6125 5500)(-6125 5600);
WIRE 17 -1 (-6125 5400)(-6125 5500);
WIRE 17 -1 (-6125 5300)(-6125 5400);
WIRE 17 -1 (-6125 5300)(-6125 5200);
WIRE 17 -1 (-5925 6050)(-5925 5950);
WIRE 17 -1 (-5925 6050)(-6725 6050);
FORCEPROP 2 LAST SIG_NAME M_B_CPU1_SA_DQS_DP<9:0>
J 2
(-6160 6060);
DISPLAY 0.489362 (-6160 6060);
WIRE 17 -1 (-6125 5200)(-6125 5100);
WIRE 17 -1 (-5925 5950)(-5925 5850);
WIRE 17 -1 (-5925 5850)(-5925 5750);
WIRE 17 -1 (-5925 5750)(-5925 5650);
WIRE 17 -1 (-5925 5550)(-5925 5650);
WIRE 17 -1 (-5925 5450)(-5925 5550);
WIRE 17 -1 (-5925 5350)(-5925 5450);
WIRE 17 -1 (-5925 5350)(-5925 5250);
WIRE 17 -1 (-5925 5250)(-5925 5150);
WIRE 17 -1 (-5925 4500)(-5925 4600);
WIRE 17 -1 (-5925 4400)(-5925 4500);
WIRE 17 -1 (-5925 4700)(-5925 4600);
WIRE 17 -1 (-5925 4800)(-5925 4700);
WIRE 17 -1 (-5925 4300)(-5925 4400);
WIRE 17 -1 (-5925 4300)(-5925 4200);
WIRE 17 -1 (-5925 4900)(-5925 4800);
WIRE 17 -1 (-5925 5000)(-5925 4900);
WIRE 17 -1 (-5925 4200)(-5925 4100);
WIRE 17 -1 (-5925 5000)(-6725 5000);
FORCEPROP 2 LAST SIG_NAME M_B_CPU1_SB_DQS_DP<9:0>
J 2
(-6160 5010);
DISPLAY 0.489362 (-6160 5010);
WIRE 17 -1 (-6125 4950)(-6125 4850);
FORCEPROP 2 LAST SIG_NAME M_B_CPU1_SB_DQS_DN<9:0>
J 2
(-6160 4960);
DISPLAY 0.489362 (-6160 4960);
WIRE 17 -1 (-6125 4750)(-6125 4650);
WIRE 17 -1 (-6125 4850)(-6125 4750);
WIRE 17 -1 (-6125 4650)(-6125 4550);
WIRE 17 -1 (-6125 4450)(-6125 4550);
WIRE 17 -1 (-6125 4350)(-6125 4450);
WIRE 17 -1 (-6125 4250)(-6125 4350);
WIRE 17 -1 (-6125 4250)(-6125 4150);
WIRE 17 -1 (-6125 4150)(-6125 4050);
WIRE 17 -1 (-6125 3850)(-6125 3900);
WIRE 17 -1 (-6125 3800)(-6125 3850);
WIRE 17 -1 (-6125 3900)(-6625 3900);
FORCEPROP 2 LAST SIG_NAME M_B_CPU1_SA_CA<6:0>
J 0
(-6625 3910);
DISPLAY 0.489362 (-6625 3910);
WIRE 17 -1 (-6125 3450)(-6125 3500);
WIRE 17 -1 (-6125 3400)(-6125 3450);
WIRE 17 -1 (-6125 3500)(-6625 3500);
FORCEPROP 2 LAST SIG_NAME M_B_CPU1_SB_CA<6:0>
J 0
(-6625 3510);
DISPLAY 0.489362 (-6625 3510);
WIRE 17 -1 (-6125 3750)(-6125 3800);
WIRE 17 -1 (-6125 3350)(-6125 3400);
WIRE 17 -1 (-6125 3700)(-6125 3750);
WIRE 17 -1 (-6125 3650)(-6125 3700);
WIRE 17 -1 (-6125 3600)(-6125 3650);
WIRE 17 -1 (-6125 3300)(-6125 3350);
WIRE 17 -1 (-6125 3250)(-6125 3300);
WIRE 17 -1 (-6125 3200)(-6125 3250);
WIRE 17 -1 (-6125 6000)(-6725 6000);
WIRE 17 -1 (-6125 4950)(-6725 4950);
WIRE 16 -1 (-7575 2175)(-6850 2175);
FORCEPROP 2 LAST SIG_NAME M_B_CPU1_ALERT_N
J 0
(-7535 2185);
DISPLAY 0.489362 (-7535 2185);
WIRE 16 -1 (-6625 1225)(-5525 1225);
FORCEPROP 2 LAST SIG_NAME TP_M_B_CPU1_SA_TEST39B
J 0
(-6610 1235);
DISPLAY 0.489362 (-6610 1235);
FORCEPROP 2 LASTPROP $XRERR UNIQUE?
J 0
(-6865 1225);
DISPLAY 0.638298 (-6865 1225);
PAINT MONO (-6865 1225);
DISPLAY INVISIBLE (-6865 1225);
WIRE 16 -1 (-6650 2175)(-5525 2175);
FORCEPROP 2 LAST SIG_NAME M_B_CPU1_ALERT_R_N
J 0
(-6360 2185);
DISPLAY 0.489362 (-6360 2185);
FORCEPROP 2 LASTPROP $XRERR UNIQUE?
J 0
(-6600 2185);
DISPLAY 0.638298 (-6600 2185);
PAINT MONO (-6600 2185);
DISPLAY INVISIBLE (-6600 2185);
WIRE 16 -1 (-6625 3025)(-5525 3025);
FORCEPROP 2 LAST SIG_NAME M_B_CPU1_CLK_DP<0>
J 0
(-6625 3035);
DISPLAY 0.489362 (-6625 3035);
WIRE 16 -1 (-6625 2975)(-5525 2975);
FORCEPROP 2 LAST SIG_NAME M_B_CPU1_CLK_DN<0>
J 0
(-6625 2985);
DISPLAY 0.489362 (-6625 2985);
WIRE 16 -1 (-6625 2875)(-5525 2875);
FORCEPROP 2 LAST SIG_NAME M_B_CPU1_SA_CS_N<0>
J 0
(-6625 2885);
DISPLAY 0.489362 (-6625 2885);
WIRE 16 -1 (-6625 2825)(-5525 2825);
FORCEPROP 2 LAST SIG_NAME M_B_CPU1_SA_CS_N<1>
J 0
(-6625 2835);
DISPLAY 0.489362 (-6625 2835);
WIRE 16 -1 (-6625 2725)(-5525 2725);
FORCEPROP 2 LAST SIG_NAME M_B_CPU1_SA_RSP<0>
J 0
(-6625 2735);
DISPLAY 0.489362 (-6625 2735);
WIRE 16 -1 (-6625 2625)(-5525 2625);
FORCEPROP 2 LAST SIG_NAME M_B_CPU1_SA_PAR
J 0
(-6625 2635);
DISPLAY 0.489362 (-6625 2635);
WIRE 16 -1 (-6625 2475)(-5525 2475);
FORCEPROP 2 LAST SIG_NAME M_B_CPU1_SB_CS_N<1>
J 0
(-6625 2485);
DISPLAY 0.489362 (-6625 2485);
WIRE 16 -1 (-6625 2525)(-5525 2525);
FORCEPROP 2 LAST SIG_NAME M_B_CPU1_SB_CS_N<0>
J 0
(-6625 2535);
DISPLAY 0.489362 (-6625 2535);
WIRE 16 -1 (-6625 2375)(-5525 2375);
FORCEPROP 2 LAST SIG_NAME M_B_CPU1_SB_RSP<0>
J 0
(-6625 2385);
DISPLAY 0.489362 (-6625 2385);
WIRE 16 -1 (-6625 2275)(-5525 2275);
FORCEPROP 2 LAST SIG_NAME M_B_CPU1_SB_PAR
J 0
(-6625 2285);
DISPLAY 0.489362 (-6625 2285);
WIRE 16 -1 (-6625 2075)(-5525 2075);
FORCEPROP 2 LAST SIG_NAME M_B_CPU1_RESET_N
J 0
(-6625 2085);
DISPLAY 0.489362 (-6625 2085);
WIRE 16 -1 (-5825 4075)(-5525 4075);
WIRE 16 -1 (-6025 3175)(-5525 3175);
WIRE 16 -1 (-6025 3575)(-5525 3575);
WIRE 16 -1 (-6025 3225)(-5525 3225);
WIRE 16 -1 (-6025 3625)(-5525 3625);
WIRE 16 -1 (-6025 3275)(-5525 3275);
WIRE 16 -1 (-6025 3675)(-5525 3675);
WIRE 16 -1 (-6025 3325)(-5525 3325);
WIRE 16 -1 (-6025 3725)(-5525 3725);
WIRE 16 -1 (-6025 3375)(-5525 3375);
WIRE 16 -1 (-6025 3775)(-5525 3775);
WIRE 16 -1 (-6025 3425)(-5525 3425);
WIRE 16 -1 (-6025 3825)(-5525 3825);
WIRE 16 -1 (-6025 3475)(-5525 3475);
WIRE 16 -1 (-6025 3875)(-5525 3875);
WIRE 16 -1 (-6025 4025)(-5525 4025);
WIRE 16 -1 (-5825 4575)(-5525 4575);
WIRE 16 -1 (-6025 4125)(-5525 4125);
WIRE 16 -1 (-5825 4675)(-5525 4675);
WIRE 16 -1 (-6025 4225)(-5525 4225);
WIRE 16 -1 (-5825 4775)(-5525 4775);
WIRE 16 -1 (-6025 4325)(-5525 4325);
WIRE 16 -1 (-5825 4875)(-5525 4875);
WIRE 16 -1 (-6025 4425)(-5525 4425);
WIRE 16 -1 (-5825 4975)(-5525 4975);
WIRE 16 -1 (-6025 4525)(-5525 4525);
WIRE 16 -1 (-6025 5075)(-5525 5075);
WIRE 16 -1 (-6025 4625)(-5525 4625);
WIRE 16 -1 (-6025 4725)(-5525 4725);
WIRE 16 -1 (-6025 4825)(-5525 4825);
WIRE 16 -1 (-6025 4925)(-5525 4925);
WIRE 16 -1 (-5825 4175)(-5525 4175);
WIRE 16 -1 (-5825 4275)(-5525 4275);
WIRE 16 -1 (-5825 4375)(-5525 4375);
WIRE 16 -1 (-5825 4475)(-5525 4475);
WIRE 16 -1 (-5825 5125)(-5525 5125);
WIRE 16 -1 (-5825 5225)(-5525 5225);
WIRE 16 -1 (-5825 5325)(-5525 5325);
WIRE 16 -1 (-5825 5425)(-5525 5425);
WIRE 16 -1 (-5825 5525)(-5525 5525);
WIRE 16 -1 (-5825 5625)(-5525 5625);
WIRE 16 -1 (-6025 5175)(-5525 5175);
WIRE 16 -1 (-5825 5725)(-5525 5725);
WIRE 16 -1 (-6025 5275)(-5525 5275);
WIRE 16 -1 (-5825 5825)(-5525 5825);
WIRE 16 -1 (-6025 5375)(-5525 5375);
WIRE 16 -1 (-5825 5925)(-5525 5925);
WIRE 16 -1 (-6025 5475)(-5525 5475);
WIRE 16 -1 (-5825 6025)(-5525 6025);
WIRE 16 -1 (-6025 5575)(-5525 5575);
WIRE 16 -1 (-6025 5675)(-5525 5675);
WIRE 16 -1 (-6025 5775)(-5525 5775);
WIRE 16 -1 (-6025 5875)(-5525 5875);
WIRE 16 -1 (-6025 5975)(-5525 5975);
WIRE 16 -1 (-3925 1625)(-3500 1625);
WIRE 16 -1 (-3925 1675)(-3500 1675);
WIRE 16 -1 (-3925 1725)(-3500 1725);
WIRE 16 -1 (-3925 1775)(-3500 1775);
WIRE 16 -1 (-3925 1825)(-3500 1825);
WIRE 16 -1 (-3925 1875)(-3500 1875);
WIRE 16 -1 (-3925 1925)(-3500 1925);
WIRE 16 -1 (-3925 1975)(-3500 1975);
WIRE 16 -1 (-3925 2375)(-3500 2375);
WIRE 16 -1 (-3925 2425)(-3500 2425);
WIRE 16 -1 (-3925 2625)(-3500 2625);
WIRE 16 -1 (-3925 2675)(-3500 2675);
WIRE 16 -1 (-3925 2725)(-3500 2725);
WIRE 16 -1 (-3925 2775)(-3500 2775);
WIRE 16 -1 (-3925 2825)(-3500 2825);
WIRE 16 -1 (-3925 2875)(-3500 2875);
WIRE 16 -1 (-3925 2975)(-3500 2975);
WIRE 16 -1 (-3925 3025)(-3500 3025);
WIRE 16 -1 (-3925 2075)(-3500 2075);
WIRE 16 -1 (-3925 2125)(-3500 2125);
WIRE 16 -1 (-3925 2525)(-3500 2525);
WIRE 16 -1 (-3925 2175)(-3500 2175);
WIRE 16 -1 (-3925 2575)(-3500 2575);
WIRE 16 -1 (-3925 2225)(-3500 2225);
WIRE 16 -1 (-3925 2275)(-3500 2275);
WIRE 16 -1 (-3925 2325)(-3500 2325);
WIRE 16 -1 (-3925 3125)(-3500 3125);
WIRE 16 -1 (-3925 3175)(-3500 3175);
WIRE 16 -1 (-3925 3225)(-3500 3225);
WIRE 16 -1 (-3925 3725)(-3500 3725);
WIRE 16 -1 (-3925 3275)(-3500 3275);
WIRE 16 -1 (-3925 3775)(-3500 3775);
WIRE 16 -1 (-3925 3325)(-3500 3325);
WIRE 16 -1 (-3925 3875)(-3500 3875);
WIRE 16 -1 (-3925 3425)(-3500 3425);
WIRE 16 -1 (-3925 3925)(-3500 3925);
WIRE 16 -1 (-3925 3475)(-3500 3475);
WIRE 16 -1 (-3925 3975)(-3500 3975);
WIRE 16 -1 (-3925 3525)(-3500 3525);
WIRE 16 -1 (-3925 4025)(-3500 4025);
WIRE 16 -1 (-3925 3575)(-3500 3575);
WIRE 16 -1 (-3925 4075)(-3500 4075);
WIRE 16 -1 (-3925 3625)(-3500 3625);
WIRE 16 -1 (-3925 3675)(-3500 3675);
WIRE 16 -1 (-3925 3075)(-3500 3075);
WIRE 16 -1 (-3925 4675)(-3500 4675);
WIRE 16 -1 (-3925 4875)(-3500 4875);
WIRE 16 -1 (-3925 4925)(-3500 4925);
WIRE 16 -1 (-3925 4325)(-3500 4325);
WIRE 16 -1 (-3925 4375)(-3500 4375);
WIRE 16 -1 (-3925 4975)(-3500 4975);
WIRE 16 -1 (-3925 5025)(-3500 5025);
WIRE 16 -1 (-3925 4425)(-3500 4425);
WIRE 16 -1 (-3925 5075)(-3500 5075);
WIRE 16 -1 (-3925 4475)(-3500 4475);
WIRE 16 -1 (-3925 4525)(-3500 4525);
WIRE 16 -1 (-3925 4125)(-3500 4125);
WIRE 16 -1 (-3925 4575)(-3500 4575);
WIRE 16 -1 (-3925 4175)(-3500 4175);
WIRE 16 -1 (-3925 4625)(-3500 4625);
WIRE 16 -1 (-3925 4225)(-3500 4225);
WIRE 16 -1 (-3925 4775)(-3500 4775);
WIRE 16 -1 (-3925 4825)(-3500 4825);
WIRE 16 -1 (-3925 5475)(-3500 5475);
WIRE 16 -1 (-3925 5525)(-3500 5525);
WIRE 16 -1 (-3925 5575)(-3500 5575);
WIRE 16 -1 (-3925 5675)(-3500 5675);
WIRE 16 -1 (-3925 5725)(-3500 5725);
WIRE 16 -1 (-3925 5775)(-3500 5775);
WIRE 16 -1 (-3925 5825)(-3500 5825);
WIRE 16 -1 (-3925 5875)(-3500 5875);
WIRE 16 -1 (-3925 5125)(-3500 5125);
WIRE 16 -1 (-3925 5925)(-3500 5925);
WIRE 16 -1 (-3925 5225)(-3500 5225);
WIRE 16 -1 (-3925 5975)(-3500 5975);
WIRE 16 -1 (-3925 5275)(-3500 5275);
WIRE 16 -1 (-3925 6025)(-3500 6025);
WIRE 16 -1 (-3925 5325)(-3500 5325);
WIRE 16 -1 (-3925 5375)(-3500 5375);
WIRE 16 -1 (-3925 5425)(-3500 5425);
QUIT
